(kicad_sch
	(version 20250114)
	(generator "eeschema")
	(generator_version "9.0")
	(paper "A3")
	(title_block
		(title "PolarFire SoM")
		(date "2025-07-22")
		(rev "1.1.4")
		(company "Antmicro Ltd")
		(comment 1 "www.antmicro.com")
	)
	(text "JTAG"
		(exclude_from_sim no)
		(at 198.12 203.2 0)
		(effects
			(font
				(size 4 4)
				(thickness 0.8)
				(bold yes)
			)
			(justify left bottom)
		)
	)
	(text "SPI FLASH"
		(exclude_from_sim no)
		(at 185.42 146.05 0)
		(effects
			(font
				(size 4 4)
				(thickness 0.8)
				(bold yes)
			)
			(justify left bottom)
		)
	)
	(text "PolarFire Bank 3\nJTAG/DEDIO"
		(exclude_from_sim no)
		(at 15.875 27.94 0)
		(effects
			(font
				(size 4 4)
				(thickness 0.8)
				(bold yes)
			)
			(justify left bottom)
		)
	)
	(junction
		(at 158.75 83.82)
		(diameter 0)
		(color 0 0 0 0)
	)
	(junction
		(at 158.75 87.63)
		(diameter 0)
		(color 0 0 0 0)
	)
	(junction
		(at 224.79 99.06)
		(diameter 0)
		(color 0 0 0 0)
	)
	(junction
		(at 219.71 88.9)
		(diameter 0)
		(color 0 0 0 0)
	)
	(junction
		(at 256.54 93.98)
		(diameter 0)
		(color 0 0 0 0)
	)
	(junction
		(at 217.17 86.36)
		(diameter 0)
		(color 0 0 0 0)
	)
	(no_connect
		(at 191.77 223.52)
	)
	(no_connect
		(at 220.98 223.52)
	)
	(wire
		(pts
			(xy 170.18 87.63) (xy 175.26 87.63)
		)
		(stroke
			(width 0)
			(type default)
		)
	)
	(wire
		(pts
			(xy 223.52 218.44) (xy 220.98 218.44)
		)
		(stroke
			(width 0)
			(type default)
		)
	)
	(wire
		(pts
			(xy 170.18 101.6) (xy 180.34 101.6)
		)
		(stroke
			(width 0)
			(type default)
		)
	)
	(wire
		(pts
			(xy 170.18 99.06) (xy 180.34 99.06)
		)
		(stroke
			(width 0)
			(type default)
		)
	)
	(wire
		(pts
			(xy 224.79 74.93) (xy 224.79 76.2)
		)
		(stroke
			(width 0)
			(type default)
		)
	)
	(wire
		(pts
			(xy 217.17 74.93) (xy 217.17 76.2)
		)
		(stroke
			(width 0)
			(type default)
		)
	)
	(wire
		(pts
			(xy 266.7 96.52) (xy 271.78 96.52)
		)
		(stroke
			(width 0)
			(type default)
		)
	)
	(wire
		(pts
			(xy 158.75 91.44) (xy 165.1 91.44)
		)
		(stroke
			(width 0)
			(type default)
		)
	)
	(wire
		(pts
			(xy 189.23 215.9) (xy 191.77 215.9)
		)
		(stroke
			(width 0)
			(type default)
		)
	)
	(wire
		(pts
			(xy 222.25 215.9) (xy 222.25 229.87)
		)
		(stroke
			(width 0)
			(type default)
		)
	)
	(wire
		(pts
			(xy 158.75 87.63) (xy 158.75 91.44)
		)
		(stroke
			(width 0)
			(type default)
		)
	)
	(wire
		(pts
			(xy 158.75 87.63) (xy 165.1 87.63)
		)
		(stroke
			(width 0)
			(type default)
		)
	)
	(wire
		(pts
			(xy 176.53 83.82) (xy 170.18 83.82)
		)
		(stroke
			(width 0)
			(type default)
		)
	)
	(wire
		(pts
			(xy 215.9 86.36) (xy 217.17 86.36)
		)
		(stroke
			(width 0)
			(type default)
		)
	)
	(wire
		(pts
			(xy 227.33 168.91) (xy 227.33 167.64)
		)
		(stroke
			(width 0)
			(type default)
		)
	)
	(wire
		(pts
			(xy 176.53 86.36) (xy 176.53 83.82)
		)
		(stroke
			(width 0)
			(type default)
		)
	)
	(wire
		(pts
			(xy 170.18 91.44) (xy 180.34 91.44)
		)
		(stroke
			(width 0)
			(type default)
		)
	)
	(wire
		(pts
			(xy 236.22 171.45) (xy 236.22 167.64)
		)
		(stroke
			(width 0)
			(type default)
		)
	)
	(wire
		(pts
			(xy 219.71 88.9) (xy 228.6 88.9)
		)
		(stroke
			(width 0)
			(type default)
		)
	)
	(wire
		(pts
			(xy 179.07 171.45) (xy 172.72 171.45)
		)
		(stroke
			(width 0)
			(type default)
		)
	)
	(wire
		(pts
			(xy 222.25 215.9) (xy 220.98 215.9)
		)
		(stroke
			(width 0)
			(type default)
		)
	)
	(wire
		(pts
			(xy 227.33 160.02) (xy 227.33 162.56)
		)
		(stroke
			(width 0)
			(type default)
		)
	)
	(wire
		(pts
			(xy 201.93 168.91) (xy 227.33 168.91)
		)
		(stroke
			(width 0)
			(type default)
		)
	)
	(wire
		(pts
			(xy 220.98 220.98) (xy 223.52 220.98)
		)
		(stroke
			(width 0)
			(type default)
		)
	)
	(wire
		(pts
			(xy 175.26 87.63) (xy 175.26 88.9)
		)
		(stroke
			(width 0)
			(type default)
		)
	)
	(wire
		(pts
			(xy 201.93 166.37) (xy 213.36 166.37)
		)
		(stroke
			(width 0)
			(type default)
		)
	)
	(wire
		(pts
			(xy 180.34 86.36) (xy 176.53 86.36)
		)
		(stroke
			(width 0)
			(type default)
		)
	)
	(wire
		(pts
			(xy 190.5 229.87) (xy 190.5 218.44)
		)
		(stroke
			(width 0)
			(type default)
		)
	)
	(wire
		(pts
			(xy 236.22 160.02) (xy 236.22 162.56)
		)
		(stroke
			(width 0)
			(type default)
		)
	)
	(wire
		(pts
			(xy 158.75 83.82) (xy 165.1 83.82)
		)
		(stroke
			(width 0)
			(type default)
		)
	)
	(wire
		(pts
			(xy 261.62 96.52) (xy 256.54 96.52)
		)
		(stroke
			(width 0)
			(type default)
		)
	)
	(wire
		(pts
			(xy 170.18 96.52) (xy 180.34 96.52)
		)
		(stroke
			(width 0)
			(type default)
		)
	)
	(wire
		(pts
			(xy 201.93 163.83) (xy 213.36 163.83)
		)
		(stroke
			(width 0)
			(type default)
		)
	)
	(wire
		(pts
			(xy 167.64 168.91) (xy 179.07 168.91)
		)
		(stroke
			(width 0)
			(type default)
		)
	)
	(wire
		(pts
			(xy 217.17 81.28) (xy 217.17 86.36)
		)
		(stroke
			(width 0)
			(type default)
		)
	)
	(wire
		(pts
			(xy 171.45 163.83) (xy 171.45 160.02)
		)
		(stroke
			(width 0)
			(type default)
		)
	)
	(wire
		(pts
			(xy 175.26 88.9) (xy 180.34 88.9)
		)
		(stroke
			(width 0)
			(type default)
		)
	)
	(wire
		(pts
			(xy 266.7 93.98) (xy 271.78 93.98)
		)
		(stroke
			(width 0)
			(type default)
		)
	)
	(wire
		(pts
			(xy 217.17 86.36) (xy 240.03 86.36)
		)
		(stroke
			(width 0)
			(type default)
		)
	)
	(wire
		(pts
			(xy 158.75 83.82) (xy 158.75 87.63)
		)
		(stroke
			(width 0)
			(type default)
		)
	)
	(wire
		(pts
			(xy 252.73 160.02) (xy 252.73 162.56)
		)
		(stroke
			(width 0)
			(type default)
		)
	)
	(wire
		(pts
			(xy 215.9 96.52) (xy 228.6 96.52)
		)
		(stroke
			(width 0)
			(type default)
		)
	)
	(wire
		(pts
			(xy 252.73 167.64) (xy 252.73 170.18)
		)
		(stroke
			(width 0)
			(type default)
		)
	)
	(wire
		(pts
			(xy 215.9 93.98) (xy 256.54 93.98)
		)
		(stroke
			(width 0)
			(type default)
		)
	)
	(wire
		(pts
			(xy 219.71 88.9) (xy 219.71 101.6)
		)
		(stroke
			(width 0)
			(type default)
		)
	)
	(wire
		(pts
			(xy 189.23 226.06) (xy 191.77 226.06)
		)
		(stroke
			(width 0)
			(type default)
		)
	)
	(wire
		(pts
			(xy 264.16 66.04) (xy 266.7 66.04)
		)
		(stroke
			(width 0)
			(type default)
		)
	)
	(wire
		(pts
			(xy 257.81 68.58) (xy 257.81 69.85)
		)
		(stroke
			(width 0)
			(type default)
		)
	)
	(wire
		(pts
			(xy 172.72 171.45) (xy 172.72 172.72)
		)
		(stroke
			(width 0)
			(type default)
		)
	)
	(wire
		(pts
			(xy 215.9 99.06) (xy 224.79 99.06)
		)
		(stroke
			(width 0)
			(type default)
		)
	)
	(wire
		(pts
			(xy 215.9 88.9) (xy 219.71 88.9)
		)
		(stroke
			(width 0)
			(type default)
		)
	)
	(wire
		(pts
			(xy 158.75 78.74) (xy 158.75 83.82)
		)
		(stroke
			(width 0)
			(type default)
		)
	)
	(wire
		(pts
			(xy 201.93 171.45) (xy 236.22 171.45)
		)
		(stroke
			(width 0)
			(type default)
		)
	)
	(wire
		(pts
			(xy 190.5 218.44) (xy 191.77 218.44)
		)
		(stroke
			(width 0)
			(type default)
		)
	)
	(wire
		(pts
			(xy 248.92 55.88) (xy 257.81 55.88)
		)
		(stroke
			(width 0)
			(type default)
		)
	)
	(wire
		(pts
			(xy 256.54 96.52) (xy 256.54 93.98)
		)
		(stroke
			(width 0)
			(type default)
		)
	)
	(wire
		(pts
			(xy 215.9 91.44) (xy 228.6 91.44)
		)
		(stroke
			(width 0)
			(type default)
		)
	)
	(wire
		(pts
			(xy 189.23 220.98) (xy 191.77 220.98)
		)
		(stroke
			(width 0)
			(type default)
		)
	)
	(wire
		(pts
			(xy 224.79 99.06) (xy 227.33 99.06)
		)
		(stroke
			(width 0)
			(type default)
		)
	)
	(wire
		(pts
			(xy 219.71 106.68) (xy 219.71 107.95)
		)
		(stroke
			(width 0)
			(type default)
		)
	)
	(wire
		(pts
			(xy 257.81 55.88) (xy 257.81 58.42)
		)
		(stroke
			(width 0)
			(type default)
		)
	)
	(wire
		(pts
			(xy 167.64 166.37) (xy 179.07 166.37)
		)
		(stroke
			(width 0)
			(type default)
		)
	)
	(wire
		(pts
			(xy 256.54 93.98) (xy 261.62 93.98)
		)
		(stroke
			(width 0)
			(type default)
		)
	)
	(wire
		(pts
			(xy 224.79 81.28) (xy 224.79 99.06)
		)
		(stroke
			(width 0)
			(type default)
		)
	)
	(wire
		(pts
			(xy 179.07 163.83) (xy 171.45 163.83)
		)
		(stroke
			(width 0)
			(type default)
		)
	)
	(wire
		(pts
			(xy 170.18 93.98) (xy 180.34 93.98)
		)
		(stroke
			(width 0)
			(type default)
		)
	)
	(wire
		(pts
			(xy 220.98 226.06) (xy 223.52 226.06)
		)
		(stroke
			(width 0)
			(type default)
		)
	)
	(label "DEVRST_N"
		(at 228.6 86.36 0)
		(effects
			(font
				(size 1.27 1.27)
			)
			(justify left bottom)
		)
	)
	(label "Flash.CLK"
		(at 167.64 166.37 0)
		(effects
			(font
				(size 1.27 1.27)
			)
			(justify left bottom)
		)
	)
	(label "DEVRST_N"
		(at 248.92 55.88 0)
		(effects
			(font
				(size 1.27 1.27)
			)
			(justify left bottom)
		)
	)
	(label "Flash.CS"
		(at 167.64 168.91 0)
		(effects
			(font
				(size 1.27 1.27)
			)
			(justify left bottom)
		)
	)
	(label "Flash.MISO"
		(at 170.18 99.06 0)
		(effects
			(font
				(size 1.27 1.27)
			)
			(justify left bottom)
		)
	)
	(label "Flash.CS"
		(at 170.18 101.6 0)
		(effects
			(font
				(size 1.27 1.27)
			)
			(justify left bottom)
		)
	)
	(label "Flash.MISO"
		(at 213.36 166.37 180)
		(effects
			(font
				(size 1.27 1.27)
			)
			(justify right bottom)
		)
	)
	(label "Flash.CLK"
		(at 170.18 93.98 0)
		(effects
			(font
				(size 1.27 1.27)
			)
			(justify left bottom)
		)
	)
	(label "Flash.MOSI"
		(at 213.36 163.83 180)
		(effects
			(font
				(size 1.27 1.27)
			)
			(justify right bottom)
		)
	)
	(label "Flash.MOSI"
		(at 170.18 96.52 0)
		(effects
			(font
				(size 1.27 1.27)
			)
			(justify left bottom)
		)
	)
	(global_label "JTAG_TCK"
		(shape input)
		(at 228.6 88.9 0)
		(fields_autoplaced yes)
		(effects
			(font
				(size 1.27 1.27)
			)
			(justify left)
		)
		(property "Intersheetrefs" "${INTERSHEET_REFS}"
			(at 239.7821 88.8206 0)
			(effects
				(font
					(size 1.27 1.27)
				)
				(justify left)
			)
		)
	)
	(global_label "JTAG_TDI"
		(shape output)
		(at 223.52 218.44 0)
		(fields_autoplaced yes)
		(effects
			(font
				(size 1.27 1.27)
			)
			(justify left)
		)
		(property "Intersheetrefs" "${INTERSHEET_REFS}"
			(at 234.0369 218.3606 0)
			(effects
				(font
					(size 1.27 1.27)
				)
				(justify left)
			)
		)
	)
	(global_label "JTAG_TDI"
		(shape input)
		(at 228.6 91.44 0)
		(fields_autoplaced yes)
		(effects
			(font
				(size 1.27 1.27)
			)
			(justify left)
		)
		(property "Intersheetrefs" "${INTERSHEET_REFS}"
			(at 239.1169 91.3606 0)
			(effects
				(font
					(size 1.27 1.27)
				)
				(justify left)
			)
		)
	)
	(global_label "JTAG_RESET_n"
		(shape input)
		(at 227.33 99.06 0)
		(fields_autoplaced yes)
		(effects
			(font
				(size 1.27 1.27)
			)
			(justify left)
		)
		(property "Intersheetrefs" "${INTERSHEET_REFS}"
			(at 242.8664 98.9806 0)
			(effects
				(font
					(size 1.27 1.27)
				)
				(justify left)
			)
		)
	)
	(global_label "JTAG_TDO"
		(shape output)
		(at 271.78 96.52 0)
		(fields_autoplaced yes)
		(effects
			(font
				(size 1.27 1.27)
			)
			(justify left)
		)
		(property "Intersheetrefs" "${INTERSHEET_REFS}"
			(at 283.0226 96.4406 0)
			(effects
				(font
					(size 1.27 1.27)
				)
				(justify left)
			)
		)
	)
	(global_label "PF_TDO"
		(shape output)
		(at 271.78 93.98 0)
		(fields_autoplaced yes)
		(effects
			(font
				(size 1.27 1.27)
			)
			(justify left)
		)
		(property "Intersheetrefs" "${INTERSHEET_REFS}"
			(at 281.0874 93.9006 0)
			(effects
				(font
					(size 1.27 1.27)
				)
				(justify left)
			)
		)
	)
	(global_label "JTAG_TDO"
		(shape input)
		(at 189.23 220.98 180)
		(fields_autoplaced yes)
		(effects
			(font
				(size 1.27 1.27)
			)
			(justify right)
		)
		(property "Intersheetrefs" "${INTERSHEET_REFS}"
			(at 177.4153 220.98 0)
			(effects
				(font
					(size 1.27 1.27)
				)
				(justify right)
			)
		)
	)
	(global_label "JTAG_TMS"
		(shape input)
		(at 228.6 96.52 0)
		(fields_autoplaced yes)
		(effects
			(font
				(size 1.27 1.27)
			)
			(justify left)
		)
		(property "Intersheetrefs" "${INTERSHEET_REFS}"
			(at 239.9031 96.4406 0)
			(effects
				(font
					(size 1.27 1.27)
				)
				(justify left)
			)
		)
	)
	(global_label "JTAG_TCK"
		(shape output)
		(at 189.23 215.9 180)
		(fields_autoplaced yes)
		(effects
			(font
				(size 1.27 1.27)
			)
			(justify right)
		)
		(property "Intersheetrefs" "${INTERSHEET_REFS}"
			(at 178.0479 215.8206 0)
			(effects
				(font
					(size 1.27 1.27)
				)
				(justify right)
			)
		)
	)
	(global_label "JTAG_TMS"
		(shape output)
		(at 189.23 226.06 180)
		(fields_autoplaced yes)
		(effects
			(font
				(size 1.27 1.27)
			)
			(justify right)
		)
		(property "Intersheetrefs" "${INTERSHEET_REFS}"
			(at 177.3549 226.06 0)
			(effects
				(font
					(size 1.27 1.27)
				)
				(justify right)
			)
		)
	)
	(global_label "~{PG}"
		(shape input)
		(at 266.7 66.04 0)
		(fields_autoplaced yes)
		(effects
			(font
				(size 1.27 1.27)
			)
			(justify left)
		)
		(property "Intersheetrefs" "${INTERSHEET_REFS}"
			(at 272.2252 66.04 0)
			(effects
				(font
					(size 1.27 1.27)
				)
				(justify left)
			)
		)
	)
	(global_label "JTAG_RESET_n"
		(shape output)
		(at 223.52 220.98 0)
		(fields_autoplaced yes)
		(effects
			(font
				(size 1.27 1.27)
			)
			(justify left)
		)
		(property "Intersheetrefs" "${INTERSHEET_REFS}"
			(at 239.6283 220.98 0)
			(effects
				(font
					(size 1.27 1.27)
				)
				(justify left)
			)
		)
	)
	(symbol
		(lib_id "antmicroResistors0402:R_10k_0402")
		(at 219.71 106.68 90)
		(unit 1)
		(exclude_from_sim no)
		(in_bom yes)
		(on_board yes)
		(dnp no)
		(fields_autoplaced yes)
		(property "Reference" "R43"
			(at 222.25 102.8699 90)
			(effects
				(font
					(size 1.27 1.27)
					(thickness 0.15)
				)
				(justify right)
			)
		)
		(property "Value" "R_10k_0402"
			(at 232.41 86.36 0)
			(effects
				(font
					(size 1.27 1.27)
					(thickness 0.15)
				)
				(justify left bottom)
				(hide yes)
			)
		)
		(property "Footprint" "antmicro-footprints:R_0402_1005Metric"
			(at 234.95 86.36 0)
			(effects
				(font
					(size 1.27 1.27)
					(thickness 0.15)
				)
				(justify left bottom)
				(hide yes)
			)
		)
		(property "Datasheet" "https://www.bourns.com/docs/product-datasheets/cr.pdf"
			(at 237.49 86.36 0)
			(effects
				(font
					(size 1.27 1.27)
					(thickness 0.15)
				)
				(justify left bottom)
				(hide yes)
			)
		)
		(property "Description" "SMD Chip Resistor, 10 kohm, ± 1%, 62.5 mW, 0402 [1005 Metric], Thick Film, General Purpose"
			(at 219.71 106.68 0)
			(effects
				(font
					(size 1.27 1.27)
				)
				(hide yes)
			)
		)
		(property "MPN" "CR0402-FX-1002GLF"
			(at 240.03 86.36 0)
			(effects
				(font
					(size 1.27 1.27)
					(thickness 0.15)
				)
				(justify left bottom)
				(hide yes)
			)
		)
		(property "Manufacturer" "Bourns"
			(at 242.57 86.36 0)
			(effects
				(font
					(size 1.27 1.27)
					(thickness 0.15)
				)
				(justify left bottom)
				(hide yes)
			)
		)
		(property "License" "Apache-2.0"
			(at 245.11 86.36 0)
			(effects
				(font
					(size 1.27 1.27)
					(thickness 0.15)
				)
				(justify left bottom)
				(hide yes)
			)
		)
		(property "Author" "Antmicro"
			(at 247.65 86.36 0)
			(effects
				(font
					(size 1.27 1.27)
					(thickness 0.15)
				)
				(justify left bottom)
				(hide yes)
			)
		)
		(property "Val" "10k"
			(at 222.25 105.4099 90)
			(effects
				(font
					(size 1.27 1.27)
					(thickness 0.15)
				)
				(justify right)
			)
		)
		(property "Tolerance" "1%"
			(at 229.87 86.36 0)
			(effects
				(font
					(size 1.27 1.27)
				)
				(justify left bottom)
				(hide yes)
			)
		)
		(property "Public" ""
			(at 250.19 86.36 0)
			(effects
				(font
					(size 1.27 1.27)
				)
				(justify left bottom)
				(hide yes)
			)
		)
		(pin "1"
		)
		(pin "2"
		)
		(instances
			(project "polarfire-som"
				(path ""
					(reference "R43")
					(unit 1)
				)
			)
		)
	)
	(symbol
		(lib_id "antmicroMemory:MT25QL01GBBB1EW9-0SIT")
		(at 179.07 163.83 0)
		(unit 1)
		(exclude_from_sim no)
		(in_bom yes)
		(on_board yes)
		(dnp no)
		(property "Reference" "U3"
			(at 190.5 156.21 0)
			(effects
				(font
					(size 1.27 1.27)
					(thickness 0.15)
				)
			)
		)
		(property "Value" "MT25QL01GBBB1EW9-0SIT"
			(at 222.25 171.45 0)
			(effects
				(font
					(size 1.27 1.27)
					(thickness 0.15)
				)
				(justify left bottom)
				(hide yes)
			)
		)
		(property "Footprint" "antmicro-footprints:W-PDFN-8-1EP_8x6mm_P1.27mm_EP4.3x3.4mm"
			(at 222.25 173.99 0)
			(effects
				(font
					(size 1.27 1.27)
					(thickness 0.15)
				)
				(justify left bottom)
				(hide yes)
			)
		)
		(property "Datasheet" "https://www.mouser.com/datasheet/2/671/mict_s_a0002234966_1-2290738.pdf"
			(at 222.25 176.53 0)
			(effects
				(font
					(size 1.27 1.27)
					(thickness 0.15)
				)
				(justify left bottom)
				(hide yes)
			)
		)
		(property "Description" "NOR Flash Serial-SPI 3.3V 1G-bit 1G/512M/256M x 1/2-bit/4-bit 6ns 16-Pin SOP-II T/R"
			(at 179.07 163.83 0)
			(effects
				(font
					(size 1.27 1.27)
				)
				(hide yes)
			)
		)
		(property "MPN" "MT25QL01GBBB1EW9-0SIT"
			(at 190.5 158.75 0)
			(effects
				(font
					(size 1.27 1.27)
					(thickness 0.15)
				)
			)
		)
		(property "Manufacturer" "Micron Technology"
			(at 222.25 179.07 0)
			(effects
				(font
					(size 1.27 1.27)
					(thickness 0.15)
				)
				(justify left bottom)
				(hide yes)
			)
		)
		(property "VSD_class" "SPI Flash"
			(at 222.25 181.61 0)
			(effects
				(font
					(size 1.27 1.27)
					(thickness 0.15)
				)
				(justify left bottom)
				(hide yes)
			)
		)
		(property "Author" "Antmicro"
			(at 222.25 184.15 0)
			(effects
				(font
					(size 1.27 1.27)
					(thickness 0.15)
				)
				(justify left bottom)
				(hide yes)
			)
		)
		(property "License" "Apache-2.0"
			(at 222.25 186.69 0)
			(effects
				(font
					(size 1.27 1.27)
					(thickness 0.15)
				)
				(justify left bottom)
				(hide yes)
			)
		)
		(pin "1"
		)
		(pin "2"
		)
		(pin "3"
		)
		(pin "4"
		)
		(pin "5"
		)
		(pin "6"
		)
		(pin "7"
		)
		(pin "8"
		)
		(instances
			(project "polarfire-som"
				(path ""
					(reference "U3")
					(unit 1)
				)
			)
		)
	)
	(symbol
		(lib_id "antmicroResistors0402:R_1k_0402")
		(at 224.79 81.28 90)
		(unit 1)
		(exclude_from_sim no)
		(in_bom yes)
		(on_board yes)
		(dnp no)
		(property "Reference" "R44"
			(at 226.06 77.47 90)
			(effects
				(font
					(size 1.27 1.27)
					(thickness 0.15)
				)
				(justify right)
			)
		)
		(property "Value" "R_1k_0402"
			(at 237.49 60.96 0)
			(effects
				(font
					(size 1.27 1.27)
					(thickness 0.15)
				)
				(justify left bottom)
				(hide yes)
			)
		)
		(property "Footprint" "antmicro-footprints:R_0402_1005Metric"
			(at 240.03 60.96 0)
			(effects
				(font
					(size 1.27 1.27)
					(thickness 0.15)
				)
				(justify left bottom)
				(hide yes)
			)
		)
		(property "Datasheet" "https://www.bourns.com/docs/product-datasheets/cr.pdf"
			(at 242.57 60.96 0)
			(effects
				(font
					(size 1.27 1.27)
					(thickness 0.15)
				)
				(justify left bottom)
				(hide yes)
			)
		)
		(property "Description" "SMD Chip Resistor, 1 kohm, ± 1%, 63 mW, 0402 [1005 Metric], Thick Film, General Purpose"
			(at 224.79 81.28 0)
			(effects
				(font
					(size 1.27 1.27)
				)
				(hide yes)
			)
		)
		(property "MPN" "CR0402-FX-1001GLF"
			(at 245.11 60.96 0)
			(effects
				(font
					(size 1.27 1.27)
					(thickness 0.15)
				)
				(justify left bottom)
				(hide yes)
			)
		)
		(property "Manufacturer" "Bourns"
			(at 247.65 60.96 0)
			(effects
				(font
					(size 1.27 1.27)
					(thickness 0.15)
				)
				(justify left bottom)
				(hide yes)
			)
		)
		(property "License" "Apache-2.0"
			(at 250.19 60.96 0)
			(effects
				(font
					(size 1.27 1.27)
					(thickness 0.15)
				)
				(justify left bottom)
				(hide yes)
			)
		)
		(property "Author" "Antmicro"
			(at 252.73 60.96 0)
			(effects
				(font
					(size 1.27 1.27)
					(thickness 0.15)
				)
				(justify left bottom)
				(hide yes)
			)
		)
		(property "Val" "1k"
			(at 226.06 80.01 90)
			(effects
				(font
					(size 1.27 1.27)
					(thickness 0.15)
				)
				(justify right)
			)
		)
		(property "Tolerance" "1%"
			(at 234.95 60.96 0)
			(effects
				(font
					(size 1.27 1.27)
				)
				(justify left bottom)
				(hide yes)
			)
		)
		(property "Public" ""
			(at 255.27 60.96 0)
			(effects
				(font
					(size 1.27 1.27)
				)
				(justify left bottom)
				(hide yes)
			)
		)
		(pin "2"
		)
		(pin "1"
		)
		(instances
			(project "polarfire-som"
				(path ""
					(reference "R44")
					(unit 1)
				)
			)
		)
	)
	(symbol
		(lib_id "antmicroFPGAChips:MPFS250T-FCVG484E")
		(at 180.34 86.36 0)
		(unit 4)
		(exclude_from_sim no)
		(in_bom yes)
		(on_board yes)
		(dnp no)
		(fields_autoplaced yes)
		(property "Reference" "U1"
			(at 198.12 76.2 0)
			(effects
				(font
					(size 1.27 1.27)
					(thickness 0.15)
				)
			)
		)
		(property "Value" "MPFS250T-FCVG484"
			(at 285.75 91.44 0)
			(effects
				(font
					(size 1.27 1.27)
					(thickness 0.15)
				)
				(justify left bottom)
				(hide yes)
			)
		)
		(property "Footprint" "antmicro-footprints:BGA-484_19x19mm_Layout22x22_P0.8mm_FCVG484"
			(at 285.75 93.98 0)
			(effects
				(font
					(size 1.27 1.27)
					(thickness 0.15)
				)
				(justify left bottom)
				(hide yes)
			)
		)
		(property "Datasheet" "https://ww1.microchip.com/downloads/aemDocuments/documents/FPGA/ProductDocuments/DataSheets/PolarFire-SoC-Datasheet-DS00004248.pdf"
			(at 285.75 96.52 0)
			(effects
				(font
					(size 1.27 1.27)
					(thickness 0.15)
				)
				(justify left bottom)
				(hide yes)
			)
		)
		(property "Description" "RISC-V System On Chip (SOC) IC PolarFire® FPGA - 254K Logic Modules 484-FCBGA (19x19)"
			(at 285.75 106.68 0)
			(effects
				(font
					(size 1.27 1.27)
				)
				(justify left bottom)
				(hide yes)
			)
		)
		(property "MPN" "MPFS250T-FCVG484E"
			(at 198.12 78.74 0)
			(effects
				(font
					(size 1.27 1.27)
					(thickness 0.15)
				)
			)
		)
		(property "Manufacturer" "Microchip Technology"
			(at 285.75 99.06 0)
			(effects
				(font
					(size 1.27 1.27)
					(thickness 0.15)
				)
				(justify left bottom)
				(hide yes)
			)
		)
		(property "VSD_class" "MPFS250T"
			(at 284.48 104.14 0)
			(effects
				(font
					(size 1.27 1.27)
					(thickness 0.15)
				)
				(justify left bottom)
				(hide yes)
			)
		)
		(property "Author" "Antmicro"
			(at 285.75 101.6 0)
			(effects
				(font
					(size 1.27 1.27)
					(thickness 0.15)
				)
				(justify left bottom)
				(hide yes)
			)
		)
		(property "License" "Apache-2.0"
			(at 285.75 104.14 0)
			(effects
				(font
					(size 1.27 1.27)
					(thickness 0.15)
				)
				(justify left bottom)
				(hide yes)
			)
		)
		(pin "AA12"
		)
		(pin "AA13"
		)
		(pin "AA15"
		)
		(pin "AA16"
		)
		(pin "AA17"
		)
		(pin "AA18"
		)
		(pin "AA20"
		)
		(pin "AA21"
		)
		(pin "AA22"
		)
		(pin "AB12"
		)
		(pin "AB13"
		)
		(pin "AB14"
		)
		(pin "AB15"
		)
		(pin "AB17"
		)
		(pin "AB18"
		)
		(pin "AB19"
		)
		(pin "AB20"
		)
		(pin "AB21"
		)
		(pin "R12"
		)
		(pin "R14"
		)
		(pin "R15"
		)
		(pin "R16"
		)
		(pin "T12"
		)
		(pin "T13"
		)
		(pin "T15"
		)
		(pin "T16"
		)
		(pin "T17"
		)
		(pin "U12"
		)
		(pin "U13"
		)
		(pin "U14"
		)
		(pin "U15"
		)
		(pin "U17"
		)
		(pin "U18"
		)
		(pin "U19"
		)
		(pin "V12"
		)
		(pin "V14"
		)
		(pin "V15"
		)
		(pin "V16"
		)
		(pin "V17"
		)
		(pin "V19"
		)
		(pin "V20"
		)
		(pin "V21"
		)
		(pin "V22"
		)
		(pin "W12"
		)
		(pin "W13"
		)
		(pin "W14"
		)
		(pin "W16"
		)
		(pin "W17"
		)
		(pin "W18"
		)
		(pin "W19"
		)
		(pin "W21"
		)
		(pin "W22"
		)
		(pin "Y13"
		)
		(pin "Y14"
		)
		(pin "Y15"
		)
		(pin "Y16"
		)
		(pin "Y18"
		)
		(pin "Y19"
		)
		(pin "Y20"
		)
		(pin "Y21"
		)
		(pin "A10"
		)
		(pin "A11"
		)
		(pin "A12"
		)
		(pin "A13"
		)
		(pin "A15"
		)
		(pin "A16"
		)
		(pin "A17"
		)
		(pin "A18"
		)
		(pin "A20"
		)
		(pin "A21"
		)
		(pin "A5"
		)
		(pin "A6"
		)
		(pin "A7"
		)
		(pin "A8"
		)
		(pin "B10"
		)
		(pin "B12"
		)
		(pin "B13"
		)
		(pin "B14"
		)
		(pin "B15"
		)
		(pin "B17"
		)
		(pin "B18"
		)
		(pin "B19"
		)
		(pin "B20"
		)
		(pin "B21"
		)
		(pin "B22"
		)
		(pin "B4"
		)
		(pin "B5"
		)
		(pin "B7"
		)
		(pin "B8"
		)
		(pin "B9"
		)
		(pin "C10"
		)
		(pin "C11"
		)
		(pin "C12"
		)
		(pin "C14"
		)
		(pin "C15"
		)
		(pin "C16"
		)
		(pin "C17"
		)
		(pin "C19"
		)
		(pin "C20"
		)
		(pin "C22"
		)
		(pin "C4"
		)
		(pin "C5"
		)
		(pin "C6"
		)
		(pin "C7"
		)
		(pin "C9"
		)
		(pin "D11"
		)
		(pin "D12"
		)
		(pin "D13"
		)
		(pin "D14"
		)
		(pin "D16"
		)
		(pin "D17"
		)
		(pin "D18"
		)
		(pin "D19"
		)
		(pin "D20"
		)
		(pin "D21"
		)
		(pin "D22"
		)
		(pin "D6"
		)
		(pin "D7"
		)
		(pin "D8"
		)
		(pin "D9"
		)
		(pin "E10"
		)
		(pin "E11"
		)
		(pin "E13"
		)
		(pin "E14"
		)
		(pin "E15"
		)
		(pin "E16"
		)
		(pin "E18"
		)
		(pin "E19"
		)
		(pin "F10"
		)
		(pin "F11"
		)
		(pin "F12"
		)
		(pin "F13"
		)
		(pin "F15"
		)
		(pin "F16"
		)
		(pin "F17"
		)
		(pin "G12"
		)
		(pin "G13"
		)
		(pin "G14"
		)
		(pin "G15"
		)
		(pin "G17"
		)
		(pin "H12"
		)
		(pin "H13"
		)
		(pin "H15"
		)
		(pin "H17"
		)
		(pin "A2"
		)
		(pin "A3"
		)
		(pin "B1"
		)
		(pin "B2"
		)
		(pin "B3"
		)
		(pin "C1"
		)
		(pin "C2"
		)
		(pin "D1"
		)
		(pin "D2"
		)
		(pin "D3"
		)
		(pin "D4"
		)
		(pin "E1"
		)
		(pin "E3"
		)
		(pin "E4"
		)
		(pin "E5"
		)
		(pin "F1"
		)
		(pin "F2"
		)
		(pin "F3"
		)
		(pin "F5"
		)
		(pin "F6"
		)
		(pin "G2"
		)
		(pin "G3"
		)
		(pin "G4"
		)
		(pin "G5"
		)
		(pin "E6"
		)
		(pin "E8"
		)
		(pin "E9"
		)
		(pin "F7"
		)
		(pin "F8"
		)
		(pin "G10"
		)
		(pin "G7"
		)
		(pin "G8"
		)
		(pin "G9"
		)
		(pin "H10"
		)
		(pin "H11"
		)
		(pin "H7"
		)
		(pin "H9"
		)
		(pin "H1"
		)
		(pin "H2"
		)
		(pin "H4"
		)
		(pin "H5"
		)
		(pin "H6"
		)
		(pin "J1"
		)
		(pin "J2"
		)
		(pin "J3"
		)
		(pin "J4"
		)
		(pin "J6"
		)
		(pin "J7"
		)
		(pin "K3"
		)
		(pin "K4"
		)
		(pin "K5"
		)
		(pin "K6"
		)
		(pin "K7"
		)
		(pin "L5"
		)
		(pin "L6"
		)
		(pin "L7"
		)
		(pin "L8"
		)
		(pin "M7"
		)
		(pin "N6"
		)
		(pin "N7"
		)
		(pin "N8"
		)
		(pin "AA1"
		)
		(pin "AA10"
		)
		(pin "AA11"
		)
		(pin "AA2"
		)
		(pin "AA3"
		)
		(pin "AA5"
		)
		(pin "AA6"
		)
		(pin "AA7"
		)
		(pin "AA8"
		)
		(pin "AB10"
		)
		(pin "AB2"
		)
		(pin "AB3"
		)
		(pin "AB4"
		)
		(pin "AB5"
		)
		(pin "AB7"
		)
		(pin "AB8"
		)
		(pin "AB9"
		)
		(pin "K1"
		)
		(pin "L1"
		)
		(pin "L2"
		)
		(pin "L3"
		)
		(pin "M2"
		)
		(pin "M3"
		)
		(pin "M4"
		)
		(pin "M5"
		)
		(pin "N1"
		)
		(pin "N2"
		)
		(pin "N4"
		)
		(pin "N5"
		)
		(pin "P1"
		)
		(pin "P2"
		)
		(pin "P3"
		)
		(pin "P4"
		)
		(pin "P6"
		)
		(pin "P7"
		)
		(pin "P8"
		)
		(pin "R1"
		)
		(pin "R10"
		)
		(pin "R11"
		)
		(pin "R3"
		)
		(pin "R4"
		)
		(pin "R5"
		)
		(pin "R6"
		)
		(pin "R8"
		)
		(pin "T1"
		)
		(pin "T10"
		)
		(pin "T11"
		)
		(pin "T2"
		)
		(pin "T3"
		)
		(pin "T5"
		)
		(pin "T6"
		)
		(pin "T7"
		)
		(pin "T8"
		)
		(pin "U10"
		)
		(pin "U2"
		)
		(pin "U3"
		)
		(pin "U4"
		)
		(pin "U5"
		)
		(pin "U7"
		)
		(pin "U8"
		)
		(pin "U9"
		)
		(pin "V1"
		)
		(pin "V10"
		)
		(pin "V11"
		)
		(pin "V2"
		)
		(pin "V4"
		)
		(pin "V5"
		)
		(pin "V6"
		)
		(pin "V7"
		)
		(pin "V9"
		)
		(pin "W1"
		)
		(pin "W11"
		)
		(pin "W2"
		)
		(pin "W3"
		)
		(pin "W4"
		)
		(pin "W6"
		)
		(pin "W7"
		)
		(pin "W8"
		)
		(pin "W9"
		)
		(pin "Y1"
		)
		(pin "Y10"
		)
		(pin "Y11"
		)
		(pin "Y3"
		)
		(pin "Y4"
		)
		(pin "Y5"
		)
		(pin "Y6"
		)
		(pin "Y8"
		)
		(pin "Y9"
		)
		(pin "F21"
		)
		(pin "F22"
		)
		(pin "G19"
		)
		(pin "G20"
		)
		(pin "H21"
		)
		(pin "H22"
		)
		(pin "J19"
		)
		(pin "J20"
		)
		(pin "K21"
		)
		(pin "K22"
		)
		(pin "L19"
		)
		(pin "L20"
		)
		(pin "M21"
		)
		(pin "M22"
		)
		(pin "N19"
		)
		(pin "N20"
		)
		(pin "P21"
		)
		(pin "P22"
		)
		(pin "R19"
		)
		(pin "R20"
		)
		(pin "T21"
		)
		(pin "T22"
		)
		(pin "A1"
		)
		(pin "A14"
		)
		(pin "A19"
		)
		(pin "A22"
		)
		(pin "A4"
		)
		(pin "A9"
		)
		(pin "AA14"
		)
		(pin "AA19"
		)
		(pin "AA4"
		)
		(pin "AA9"
		)
		(pin "AB1"
		)
		(pin "AB11"
		)
		(pin "AB16"
		)
		(pin "AB22"
		)
		(pin "AB6"
		)
		(pin "B11"
		)
		(pin "B16"
		)
		(pin "B6"
		)
		(pin "C13"
		)
		(pin "C18"
		)
		(pin "C21"
		)
		(pin "C3"
		)
		(pin "C8"
		)
		(pin "D10"
		)
		(pin "D15"
		)
		(pin "D5"
		)
		(pin "E12"
		)
		(pin "E17"
		)
		(pin "E2"
		)
		(pin "E20"
		)
		(pin "E21"
		)
		(pin "E22"
		)
		(pin "E7"
		)
		(pin "F14"
		)
		(pin "F18"
		)
		(pin "F19"
		)
		(pin "F20"
		)
		(pin "F4"
		)
		(pin "F9"
		)
		(pin "G1"
		)
		(pin "G11"
		)
		(pin "G16"
		)
		(pin "G18"
		)
		(pin "G21"
		)
		(pin "G22"
		)
		(pin "G6"
		)
		(pin "H14"
		)
		(pin "H16"
		)
		(pin "H18"
		)
		(pin "H19"
		)
		(pin "H20"
		)
		(pin "H3"
		)
		(pin "H8"
		)
		(pin "J10"
		)
		(pin "J11"
		)
		(pin "J12"
		)
		(pin "J13"
		)
		(pin "J14"
		)
		(pin "J15"
		)
		(pin "J16"
		)
		(pin "J17"
		)
		(pin "J18"
		)
		(pin "J21"
		)
		(pin "J22"
		)
		(pin "J5"
		)
		(pin "J8"
		)
		(pin "J9"
		)
		(pin "K10"
		)
		(pin "K11"
		)
		(pin "K12"
		)
		(pin "K13"
		)
		(pin "K14"
		)
		(pin "K15"
		)
		(pin "K16"
		)
		(pin "K17"
		)
		(pin "K18"
		)
		(pin "K19"
		)
		(pin "K2"
		)
		(pin "K20"
		)
		(pin "K8"
		)
		(pin "K9"
		)
		(pin "L10"
		)
		(pin "L11"
		)
		(pin "L12"
		)
		(pin "L13"
		)
		(pin "L14"
		)
		(pin "L15"
		)
		(pin "L16"
		)
		(pin "L17"
		)
		(pin "L18"
		)
		(pin "L21"
		)
		(pin "L22"
		)
		(pin "L4"
		)
		(pin "L9"
		)
		(pin "M1"
		)
		(pin "M10"
		)
		(pin "M11"
		)
		(pin "M12"
		)
		(pin "M13"
		)
		(pin "M14"
		)
		(pin "M15"
		)
		(pin "M16"
		)
		(pin "M17"
		)
		(pin "M18"
		)
		(pin "M19"
		)
		(pin "M20"
		)
		(pin "M6"
		)
		(pin "M8"
		)
		(pin "M9"
		)
		(pin "N10"
		)
		(pin "N11"
		)
		(pin "N12"
		)
		(pin "N13"
		)
		(pin "N14"
		)
		(pin "N15"
		)
		(pin "N16"
		)
		(pin "N17"
		)
		(pin "N18"
		)
		(pin "N21"
		)
		(pin "N22"
		)
		(pin "N3"
		)
		(pin "N9"
		)
		(pin "P10"
		)
		(pin "P11"
		)
		(pin "P12"
		)
		(pin "P13"
		)
		(pin "P14"
		)
		(pin "P15"
		)
		(pin "P16"
		)
		(pin "P17"
		)
		(pin "P18"
		)
		(pin "P19"
		)
		(pin "P20"
		)
		(pin "P5"
		)
		(pin "P9"
		)
		(pin "R13"
		)
		(pin "R17"
		)
		(pin "R18"
		)
		(pin "R2"
		)
		(pin "R21"
		)
		(pin "R22"
		)
		(pin "R7"
		)
		(pin "R9"
		)
		(pin "T14"
		)
		(pin "T18"
		)
		(pin "T19"
		)
		(pin "T20"
		)
		(pin "T4"
		)
		(pin "T9"
		)
		(pin "U1"
		)
		(pin "U11"
		)
		(pin "U16"
		)
		(pin "U20"
		)
		(pin "U21"
		)
		(pin "U22"
		)
		(pin "U6"
		)
		(pin "V13"
		)
		(pin "V18"
		)
		(pin "V3"
		)
		(pin "V8"
		)
		(pin "W10"
		)
		(pin "W15"
		)
		(pin "W20"
		)
		(pin "W5"
		)
		(pin "Y12"
		)
		(pin "Y17"
		)
		(pin "Y2"
		)
		(pin "Y22"
		)
		(pin "Y7"
		)
		(instances
			(project "polarfire-som"
				(path ""
					(reference "U1")
					(unit 4)
				)
			)
		)
	)
	(symbol
		(lib_id "antmicroResistors0402:R_4k7_0402")
		(at 165.1 87.63 0)
		(unit 1)
		(exclude_from_sim no)
		(in_bom yes)
		(on_board yes)
		(dnp no)
		(property "Reference" "R40"
			(at 163.195 85.725 0)
			(effects
				(font
					(size 1.27 1.27)
					(thickness 0.15)
				)
			)
		)
		(property "Value" "R_4k7_0402"
			(at 185.42 100.33 0)
			(effects
				(font
					(size 1.27 1.27)
					(thickness 0.15)
				)
				(justify left bottom)
				(hide yes)
			)
		)
		(property "Footprint" "antmicro-footprints:R_0402_1005Metric"
			(at 185.42 102.87 0)
			(effects
				(font
					(size 1.27 1.27)
					(thickness 0.15)
				)
				(justify left bottom)
				(hide yes)
			)
		)
		(property "Datasheet" "https://www.bourns.com/docs/product-datasheets/cr.pdf"
			(at 185.42 105.41 0)
			(effects
				(font
					(size 1.27 1.27)
					(thickness 0.15)
				)
				(justify left bottom)
				(hide yes)
			)
		)
		(property "Description" "SMD Chip Resistor, 4.7 kohm, ± 1%, 62.5 mW, 0402 [1005 Metric], Thick Film, General Purpose"
			(at 165.1 87.63 0)
			(effects
				(font
					(size 1.27 1.27)
				)
				(hide yes)
			)
		)
		(property "MPN" "CR0402-FX-4701GLF"
			(at 185.42 107.95 0)
			(effects
				(font
					(size 1.27 1.27)
					(thickness 0.15)
				)
				(justify left bottom)
				(hide yes)
			)
		)
		(property "Manufacturer" "Bourns"
			(at 185.42 110.49 0)
			(effects
				(font
					(size 1.27 1.27)
					(thickness 0.15)
				)
				(justify left bottom)
				(hide yes)
			)
		)
		(property "License" "Apache-2.0"
			(at 185.42 113.03 0)
			(effects
				(font
					(size 1.27 1.27)
					(thickness 0.15)
				)
				(justify left bottom)
				(hide yes)
			)
		)
		(property "Author" "Antmicro"
			(at 185.42 115.57 0)
			(effects
				(font
					(size 1.27 1.27)
					(thickness 0.15)
				)
				(justify left bottom)
				(hide yes)
			)
		)
		(property "Val" "4k7"
			(at 171.45 85.725 0)
			(effects
				(font
					(size 1.27 1.27)
					(thickness 0.15)
				)
			)
		)
		(property "Tolerance" "1%"
			(at 185.42 97.79 0)
			(effects
				(font
					(size 1.27 1.27)
				)
				(justify left bottom)
				(hide yes)
			)
		)
		(property "Public" ""
			(at 185.42 118.11 0)
			(effects
				(font
					(size 1.27 1.27)
				)
				(justify left bottom)
				(hide yes)
			)
		)
		(pin "1"
		)
		(pin "2"
		)
		(instances
			(project "polarfire-som"
				(path ""
					(reference "R40")
					(unit 1)
				)
			)
		)
	)
	(symbol
		(lib_id "antmicroCapacitors0402:C_100n_0402")
		(at 252.73 167.64 90)
		(unit 1)
		(exclude_from_sim no)
		(in_bom yes)
		(on_board yes)
		(dnp no)
		(fields_autoplaced yes)
		(property "Reference" "C82"
			(at 255.27 163.8236 90)
			(effects
				(font
					(size 1.27 1.27)
					(thickness 0.15)
				)
				(justify right)
			)
		)
		(property "Value" "C_100n_0402"
			(at 262.89 147.32 0)
			(effects
				(font
					(size 1.27 1.27)
					(thickness 0.15)
				)
				(justify left bottom)
				(hide yes)
			)
		)
		(property "Footprint" "antmicro-footprints:C_0402_1005Metric"
			(at 265.43 147.32 0)
			(effects
				(font
					(size 1.27 1.27)
					(thickness 0.15)
				)
				(justify left bottom)
				(hide yes)
			)
		)
		(property "Datasheet" "https://www.murata.com/products/productdetail?partno=GRM155R61H104KE14%23"
			(at 267.97 147.32 0)
			(effects
				(font
					(size 1.27 1.27)
					(thickness 0.15)
				)
				(justify left bottom)
				(hide yes)
			)
		)
		(property "Description" "SMD Multilayer Ceramic Capacitor, 0.1 µF, 50 V, 0402 [1005 Metric], ± 10%, X5R, GRM Series"
			(at 252.73 167.64 0)
			(effects
				(font
					(size 1.27 1.27)
				)
				(hide yes)
			)
		)
		(property "MPN" "GRM155R61H104KE14D"
			(at 270.51 147.32 0)
			(effects
				(font
					(size 1.27 1.27)
					(thickness 0.15)
				)
				(justify left bottom)
				(hide yes)
			)
		)
		(property "Manufacturer" "Murata"
			(at 273.05 147.32 0)
			(effects
				(font
					(size 1.27 1.27)
					(thickness 0.15)
				)
				(justify left bottom)
				(hide yes)
			)
		)
		(property "License" "Apache-2.0"
			(at 275.59 147.32 0)
			(effects
				(font
					(size 1.27 1.27)
					(thickness 0.15)
				)
				(justify left bottom)
				(hide yes)
			)
		)
		(property "Author" "Antmicro"
			(at 278.13 147.32 0)
			(effects
				(font
					(size 1.27 1.27)
					(thickness 0.15)
				)
				(justify left bottom)
				(hide yes)
			)
		)
		(property "Val" "100n"
			(at 255.27 166.3636 90)
			(effects
				(font
					(size 1.27 1.27)
					(thickness 0.15)
				)
				(justify right)
			)
		)
		(property "Voltage" "50V"
			(at 280.67 147.32 0)
			(effects
				(font
					(size 1.27 1.27)
				)
				(justify left bottom)
				(hide yes)
			)
		)
		(property "Dielectric" "X5R"
			(at 283.21 147.32 0)
			(effects
				(font
					(size 1.27 1.27)
				)
				(justify left bottom)
				(hide yes)
			)
		)
		(property "Public" ""
			(at 285.75 147.32 0)
			(effects
				(font
					(size 1.27 1.27)
				)
				(justify left bottom)
				(hide yes)
			)
		)
		(pin "1"
		)
		(pin "2"
		)
		(instances
			(project "polarfire-som"
				(path ""
					(reference "C82")
					(unit 1)
				)
			)
		)
	)
	(symbol
		(lib_id "antmicroTestPoints:TP_0.75mm_SMD")
		(at 240.03 86.36 0)
		(unit 1)
		(exclude_from_sim no)
		(in_bom no)
		(on_board yes)
		(dnp no)
		(property "Reference" "TP1"
			(at 245.11 86.36 0)
			(effects
				(font
					(size 1.27 1.27)
					(thickness 0.15)
				)
				(justify left)
			)
		)
		(property "Value" "TP_0.75mm_SMD"
			(at 250.825 90.17 0)
			(effects
				(font
					(size 1.27 1.27)
					(thickness 0.15)
				)
				(justify left bottom)
				(hide yes)
			)
		)
		(property "Footprint" "antmicro-footprints:TP_SMD_0.75mm"
			(at 250.825 92.71 0)
			(effects
				(font
					(size 1.27 1.27)
					(thickness 0.15)
				)
				(justify left bottom)
				(hide yes)
			)
		)
		(property "Datasheet" ""
			(at 257.81 99.06 0)
			(effects
				(font
					(size 1.27 1.27)
					(thickness 0.15)
				)
				(justify left bottom)
				(hide yes)
			)
		)
		(property "Description" "SMT test point"
			(at 240.03 86.36 0)
			(effects
				(font
					(size 1.27 1.27)
				)
				(hide yes)
			)
		)
		(property "MPN" ""
			(at 250.825 97.79 0)
			(effects
				(font
					(size 1.27 1.27)
					(thickness 0.15)
				)
				(justify left bottom)
				(hide yes)
			)
		)
		(property "Manufacturer" ""
			(at 250.825 92.71 0)
			(effects
				(font
					(size 1.27 1.27)
					(thickness 0.15)
				)
				(justify left bottom)
				(hide yes)
			)
		)
		(property "Author" "Antmicro"
			(at 250.825 95.25 0)
			(effects
				(font
					(size 1.27 1.27)
					(thickness 0.15)
				)
				(justify left bottom)
				(hide yes)
			)
		)
		(property "License" "Apache-2.0"
			(at 250.825 97.79 0)
			(effects
				(font
					(size 1.27 1.27)
					(thickness 0.15)
				)
				(justify left bottom)
				(hide yes)
			)
		)
		(property "Public" "False"
			(at 250.19 100.33 0)
			(effects
				(font
					(size 1.27 1.27)
				)
				(justify left bottom)
				(hide yes)
			)
		)
		(pin "1"
		)
		(instances
			(project "polarfire-som"
				(path ""
					(reference "TP1")
					(unit 1)
				)
			)
		)
	)
	(symbol
		(lib_id "antmicroTransistorsFETsMOSFETsSingle:DMG1012T-7")
		(at 264.16 66.04 0)
		(mirror y)
		(unit 1)
		(exclude_from_sim no)
		(in_bom yes)
		(on_board yes)
		(dnp no)
		(property "Reference" "Q10"
			(at 254 62.23 0)
			(effects
				(font
					(size 1.27 1.27)
					(thickness 0.15)
				)
				(justify left)
			)
		)
		(property "Value" "DMG1012T-7"
			(at 254 69.85 0)
			(effects
				(font
					(size 1.27 1.27)
					(thickness 0.15)
				)
				(justify left bottom)
				(hide yes)
			)
		)
		(property "Footprint" "antmicro-footprints:SOT-523"
			(at 254 72.39 0)
			(effects
				(font
					(size 1.27 1.27)
					(thickness 0.15)
				)
				(justify left bottom)
				(hide yes)
			)
		)
		(property "Datasheet" "https://www.diodes.com/assets/Datasheets/ds31783.pdf"
			(at 254 74.93 0)
			(effects
				(font
					(size 1.27 1.27)
					(thickness 0.15)
				)
				(justify left bottom)
				(hide yes)
			)
		)
		(property "Description" "Power MOSFET, N Channel, 20 V, 630 mA, 0.3 ohm, SOT-523, Surface Mount"
			(at 264.16 66.04 0)
			(effects
				(font
					(size 1.27 1.27)
				)
				(hide yes)
			)
		)
		(property "MPN" "DMG1012T-7"
			(at 256.286 69.342 0)
			(effects
				(font
					(size 1.27 1.27)
					(thickness 0.15)
				)
				(justify left)
			)
		)
		(property "Manufacturer" "Diodes Incorporated"
			(at 254 67.31 0)
			(effects
				(font
					(size 1.27 1.27)
					(thickness 0.15)
				)
				(justify left bottom)
				(hide yes)
			)
		)
		(property "Author" "Antmicro"
			(at 254 77.47 0)
			(effects
				(font
					(size 1.27 1.27)
					(thickness 0.15)
				)
				(justify left bottom)
				(hide yes)
			)
		)
		(property "License" "Apache-2.0"
			(at 254 80.01 0)
			(effects
				(font
					(size 1.27 1.27)
					(thickness 0.15)
				)
				(justify left bottom)
				(hide yes)
			)
		)
		(property "Public" ""
			(at 243.84 73.66 0)
			(effects
				(font
					(size 1.27 1.27)
				)
				(justify left bottom)
				(hide yes)
			)
		)
		(pin "1"
		)
		(pin "2"
		)
		(pin "3"
		)
		(instances
			(project "polarfire-som"
				(path ""
					(reference "Q10")
					(unit 1)
				)
			)
		)
	)
	(symbol
		(lib_id "antmicropower:GND")
		(at 222.25 229.87 0)
		(unit 1)
		(exclude_from_sim no)
		(in_bom yes)
		(on_board yes)
		(dnp no)
		(property "Reference" "#PWR0360"
			(at 231.14 232.41 0)
			(effects
				(font
					(size 1.27 1.27)
					(thickness 0.15)
				)
				(justify left bottom)
				(hide yes)
			)
		)
		(property "Value" "GND"
			(at 222.25 233.68 0)
			(effects
				(font
					(size 1.27 1.27)
					(thickness 0.15)
				)
			)
		)
		(property "Footprint" ""
			(at 231.14 237.49 0)
			(effects
				(font
					(size 1.27 1.27)
					(thickness 0.15)
				)
				(justify left bottom)
				(hide yes)
			)
		)
		(property "Datasheet" ""
			(at 231.14 242.57 0)
			(effects
				(font
					(size 1.27 1.27)
					(thickness 0.15)
				)
				(justify left bottom)
				(hide yes)
			)
		)
		(property "Description" ""
			(at 222.25 229.87 0)
			(effects
				(font
					(size 1.27 1.27)
				)
				(hide yes)
			)
		)
		(property "Author" "Antmicro"
			(at 231.14 237.49 0)
			(effects
				(font
					(size 1.27 1.27)
					(thickness 0.15)
				)
				(justify left bottom)
				(hide yes)
			)
		)
		(property "License" "Apache-2.0"
			(at 231.14 240.03 0)
			(effects
				(font
					(size 1.27 1.27)
					(thickness 0.15)
				)
				(justify left bottom)
				(hide yes)
			)
		)
		(pin "1"
		)
		(instances
			(project "polarfire-som"
				(path ""
					(reference "#PWR0360")
					(unit 1)
				)
			)
		)
	)
	(symbol
		(lib_id "antmicropower:+3V3")
		(at 171.45 160.02 0)
		(unit 1)
		(exclude_from_sim no)
		(in_bom yes)
		(on_board yes)
		(dnp no)
		(property "Reference" "#PWR054"
			(at 186.69 162.56 0)
			(effects
				(font
					(size 1.27 1.27)
					(thickness 0.15)
				)
				(justify left bottom)
				(hide yes)
			)
		)
		(property "Value" "+3V3"
			(at 171.45 156.21 0)
			(effects
				(font
					(size 1.27 1.27)
					(thickness 0.15)
				)
			)
		)
		(property "Footprint" ""
			(at 186.69 167.64 0)
			(effects
				(font
					(size 1.27 1.27)
					(thickness 0.15)
				)
				(justify left bottom)
				(hide yes)
			)
		)
		(property "Datasheet" ""
			(at 186.69 170.18 0)
			(effects
				(font
					(size 1.27 1.27)
					(thickness 0.15)
				)
				(justify left bottom)
				(hide yes)
			)
		)
		(property "Description" ""
			(at 171.45 160.02 0)
			(effects
				(font
					(size 1.27 1.27)
				)
				(hide yes)
			)
		)
		(property "Author" "Antmicro"
			(at 186.69 167.64 0)
			(effects
				(font
					(size 1.27 1.27)
					(thickness 0.15)
				)
				(justify left bottom)
				(hide yes)
			)
		)
		(property "License" "Apache-2.0"
			(at 186.69 170.18 0)
			(effects
				(font
					(size 1.27 1.27)
					(thickness 0.15)
				)
				(justify left bottom)
				(hide yes)
			)
		)
		(pin "1"
		)
		(instances
			(project "polarfire-som"
				(path ""
					(reference "#PWR054")
					(unit 1)
				)
			)
		)
	)
	(symbol
		(lib_id "antmicropower:GND")
		(at 252.73 170.18 0)
		(unit 1)
		(exclude_from_sim no)
		(in_bom yes)
		(on_board yes)
		(dnp no)
		(property "Reference" "#PWR059"
			(at 261.62 172.72 0)
			(effects
				(font
					(size 1.27 1.27)
					(thickness 0.15)
				)
				(justify left bottom)
				(hide yes)
			)
		)
		(property "Value" "GND"
			(at 252.73 173.99 0)
			(effects
				(font
					(size 1.27 1.27)
					(thickness 0.15)
				)
			)
		)
		(property "Footprint" ""
			(at 261.62 177.8 0)
			(effects
				(font
					(size 1.27 1.27)
					(thickness 0.15)
				)
				(justify left bottom)
				(hide yes)
			)
		)
		(property "Datasheet" ""
			(at 261.62 182.88 0)
			(effects
				(font
					(size 1.27 1.27)
					(thickness 0.15)
				)
				(justify left bottom)
				(hide yes)
			)
		)
		(property "Description" ""
			(at 252.73 170.18 0)
			(effects
				(font
					(size 1.27 1.27)
				)
				(hide yes)
			)
		)
		(property "Author" "Antmicro"
			(at 261.62 177.8 0)
			(effects
				(font
					(size 1.27 1.27)
					(thickness 0.15)
				)
				(justify left bottom)
				(hide yes)
			)
		)
		(property "License" "Apache-2.0"
			(at 261.62 180.34 0)
			(effects
				(font
					(size 1.27 1.27)
					(thickness 0.15)
				)
				(justify left bottom)
				(hide yes)
			)
		)
		(pin "1"
		)
		(instances
			(project "polarfire-som"
				(path ""
					(reference "#PWR059")
					(unit 1)
				)
			)
		)
	)
	(symbol
		(lib_id "antmicroResistors0402:R_0R_0402")
		(at 266.7 96.52 180)
		(unit 1)
		(exclude_from_sim no)
		(in_bom yes)
		(on_board yes)
		(dnp no)
		(property "Reference" "R91"
			(at 269.24 97.79 0)
			(effects
				(font
					(size 1.27 1.27)
					(thickness 0.15)
				)
			)
		)
		(property "Value" "R_0R_0402"
			(at 246.38 83.82 0)
			(effects
				(font
					(size 1.27 1.27)
					(thickness 0.15)
				)
				(justify left bottom)
				(hide yes)
			)
		)
		(property "Footprint" "antmicro-footprints:R_0402_1005Metric"
			(at 246.38 81.28 0)
			(effects
				(font
					(size 1.27 1.27)
					(thickness 0.15)
				)
				(justify left bottom)
				(hide yes)
			)
		)
		(property "Datasheet" "https://industrial.panasonic.com/cdbs/www-data/pdf/RDA0000/AOA0000C301.pdf"
			(at 246.38 78.74 0)
			(effects
				(font
					(size 1.27 1.27)
					(thickness 0.15)
				)
				(justify left bottom)
				(hide yes)
			)
		)
		(property "Description" "SMD Chip Resistor, Jumper, 0 ohm, 100 mW, 0402 [1005 Metric], Thick Film, General Purpose"
			(at 266.7 96.52 0)
			(effects
				(font
					(size 1.27 1.27)
				)
				(hide yes)
			)
		)
		(property "MPN" "ERJ2GE0R00X"
			(at 246.38 76.2 0)
			(effects
				(font
					(size 1.27 1.27)
					(thickness 0.15)
				)
				(justify left bottom)
				(hide yes)
			)
		)
		(property "Manufacturer" "Panasonic"
			(at 246.38 73.66 0)
			(effects
				(font
					(size 1.27 1.27)
					(thickness 0.15)
				)
				(justify left bottom)
				(hide yes)
			)
		)
		(property "License" "Apache-2.0"
			(at 246.38 71.12 0)
			(effects
				(font
					(size 1.27 1.27)
					(thickness 0.15)
				)
				(justify left bottom)
				(hide yes)
			)
		)
		(property "Author" "Antmicro"
			(at 246.38 68.58 0)
			(effects
				(font
					(size 1.27 1.27)
					(thickness 0.15)
				)
				(justify left bottom)
				(hide yes)
			)
		)
		(property "Val" "0R"
			(at 259.08 97.79 0)
			(effects
				(font
					(size 1.27 1.27)
					(thickness 0.15)
				)
			)
		)
		(property "Tolerance" "~"
			(at 246.38 86.36 0)
			(effects
				(font
					(size 1.27 1.27)
				)
				(justify left bottom)
				(hide yes)
			)
		)
		(property "Current" "1A"
			(at 246.38 66.04 0)
			(effects
				(font
					(size 1.27 1.27)
					(thickness 0.15)
				)
				(justify left bottom)
				(hide yes)
			)
		)
		(property "DNP" "DNP"
			(at 264.16 96.52 0)
			(effects
				(font
					(size 1.27 1.27)
				)
				(hide yes)
			)
		)
		(property "Public" ""
			(at 246.38 66.04 0)
			(effects
				(font
					(size 1.27 1.27)
				)
				(justify left bottom)
				(hide yes)
			)
		)
		(pin "1"
		)
		(pin "2"
		)
		(instances
			(project "polarfire-som"
				(path ""
					(reference "R91")
					(unit 1)
				)
			)
		)
	)
	(symbol
		(lib_id "antmicroResistors0402:R_4k7_0402")
		(at 165.1 83.82 0)
		(unit 1)
		(exclude_from_sim no)
		(in_bom yes)
		(on_board yes)
		(dnp yes)
		(property "Reference" "R39"
			(at 163.195 81.915 0)
			(effects
				(font
					(size 1.27 1.27)
					(thickness 0.15)
				)
			)
		)
		(property "Value" "R_4k7_0402"
			(at 185.42 96.52 0)
			(effects
				(font
					(size 1.27 1.27)
					(thickness 0.15)
				)
				(justify left bottom)
				(hide yes)
			)
		)
		(property "Footprint" "antmicro-footprints:R_0402_1005Metric"
			(at 185.42 99.06 0)
			(effects
				(font
					(size 1.27 1.27)
					(thickness 0.15)
				)
				(justify left bottom)
				(hide yes)
			)
		)
		(property "Datasheet" "https://www.bourns.com/docs/product-datasheets/cr.pdf"
			(at 185.42 101.6 0)
			(effects
				(font
					(size 1.27 1.27)
					(thickness 0.15)
				)
				(justify left bottom)
				(hide yes)
			)
		)
		(property "Description" "SMD Chip Resistor, 4.7 kohm, ± 1%, 62.5 mW, 0402 [1005 Metric], Thick Film, General Purpose"
			(at 165.1 83.82 0)
			(effects
				(font
					(size 1.27 1.27)
				)
				(hide yes)
			)
		)
		(property "MPN" "CR0402-FX-4701GLF"
			(at 185.42 104.14 0)
			(effects
				(font
					(size 1.27 1.27)
					(thickness 0.15)
				)
				(justify left bottom)
				(hide yes)
			)
		)
		(property "Manufacturer" "Bourns"
			(at 185.42 106.68 0)
			(effects
				(font
					(size 1.27 1.27)
					(thickness 0.15)
				)
				(justify left bottom)
				(hide yes)
			)
		)
		(property "License" "Apache-2.0"
			(at 185.42 109.22 0)
			(effects
				(font
					(size 1.27 1.27)
					(thickness 0.15)
				)
				(justify left bottom)
				(hide yes)
			)
		)
		(property "Author" "Antmicro"
			(at 185.42 111.76 0)
			(effects
				(font
					(size 1.27 1.27)
					(thickness 0.15)
				)
				(justify left bottom)
				(hide yes)
			)
		)
		(property "Val" "4k7"
			(at 171.45 81.915 0)
			(effects
				(font
					(size 1.27 1.27)
					(thickness 0.15)
				)
			)
		)
		(property "Tolerance" "1%"
			(at 185.42 93.98 0)
			(effects
				(font
					(size 1.27 1.27)
				)
				(justify left bottom)
				(hide yes)
			)
		)
		(property "DNP" "DNP"
			(at 167.64 83.82 0)
			(effects
				(font
					(size 1.27 1.27)
				)
				(hide yes)
			)
		)
		(property "Public" ""
			(at 185.42 114.3 0)
			(effects
				(font
					(size 1.27 1.27)
				)
				(justify left bottom)
				(hide yes)
			)
		)
		(pin "1"
		)
		(pin "2"
		)
		(instances
			(project "polarfire-som"
				(path ""
					(reference "R39")
					(unit 1)
				)
			)
		)
	)
	(symbol
		(lib_id "antmicropower:+3V3")
		(at 224.79 74.93 0)
		(unit 1)
		(exclude_from_sim no)
		(in_bom yes)
		(on_board yes)
		(dnp no)
		(fields_autoplaced yes)
		(property "Reference" "#PWR0277"
			(at 240.03 77.47 0)
			(effects
				(font
					(size 1.27 1.27)
					(thickness 0.15)
				)
				(justify left bottom)
				(hide yes)
			)
		)
		(property "Value" "+3V3"
			(at 224.79 69.85 0)
			(effects
				(font
					(size 1.27 1.27)
					(thickness 0.15)
				)
			)
		)
		(property "Footprint" ""
			(at 240.03 82.55 0)
			(effects
				(font
					(size 1.27 1.27)
					(thickness 0.15)
				)
				(justify left bottom)
				(hide yes)
			)
		)
		(property "Datasheet" ""
			(at 240.03 85.09 0)
			(effects
				(font
					(size 1.27 1.27)
					(thickness 0.15)
				)
				(justify left bottom)
				(hide yes)
			)
		)
		(property "Description" ""
			(at 224.79 74.93 0)
			(effects
				(font
					(size 1.27 1.27)
				)
				(hide yes)
			)
		)
		(property "Author" "Antmicro"
			(at 240.03 82.55 0)
			(effects
				(font
					(size 1.27 1.27)
					(thickness 0.15)
				)
				(justify left bottom)
				(hide yes)
			)
		)
		(property "License" "Apache-2.0"
			(at 240.03 85.09 0)
			(effects
				(font
					(size 1.27 1.27)
					(thickness 0.15)
				)
				(justify left bottom)
				(hide yes)
			)
		)
		(pin "1"
		)
		(instances
			(project "polarfire-som"
				(path ""
					(reference "#PWR0277")
					(unit 1)
				)
			)
		)
	)
	(symbol
		(lib_id "antmicroResistors0402:R_10k_0402")
		(at 236.22 167.64 90)
		(unit 1)
		(exclude_from_sim no)
		(in_bom yes)
		(on_board yes)
		(dnp no)
		(fields_autoplaced yes)
		(property "Reference" "R46"
			(at 238.76 163.83 90)
			(effects
				(font
					(size 1.27 1.27)
					(thickness 0.15)
				)
				(justify right)
			)
		)
		(property "Value" "R_10k_0402"
			(at 248.92 147.32 0)
			(effects
				(font
					(size 1.27 1.27)
					(thickness 0.15)
				)
				(justify left bottom)
				(hide yes)
			)
		)
		(property "Footprint" "antmicro-footprints:R_0402_1005Metric"
			(at 251.46 147.32 0)
			(effects
				(font
					(size 1.27 1.27)
					(thickness 0.15)
				)
				(justify left bottom)
				(hide yes)
			)
		)
		(property "Datasheet" "https://www.bourns.com/docs/product-datasheets/cr.pdf"
			(at 254 147.32 0)
			(effects
				(font
					(size 1.27 1.27)
					(thickness 0.15)
				)
				(justify left bottom)
				(hide yes)
			)
		)
		(property "Description" "SMD Chip Resistor, 10 kohm, ± 1%, 62.5 mW, 0402 [1005 Metric], Thick Film, General Purpose"
			(at 236.22 167.64 0)
			(effects
				(font
					(size 1.27 1.27)
				)
				(hide yes)
			)
		)
		(property "MPN" "CR0402-FX-1002GLF"
			(at 256.54 147.32 0)
			(effects
				(font
					(size 1.27 1.27)
					(thickness 0.15)
				)
				(justify left bottom)
				(hide yes)
			)
		)
		(property "Manufacturer" "Bourns"
			(at 259.08 147.32 0)
			(effects
				(font
					(size 1.27 1.27)
					(thickness 0.15)
				)
				(justify left bottom)
				(hide yes)
			)
		)
		(property "License" "Apache-2.0"
			(at 261.62 147.32 0)
			(effects
				(font
					(size 1.27 1.27)
					(thickness 0.15)
				)
				(justify left bottom)
				(hide yes)
			)
		)
		(property "Author" "Antmicro"
			(at 264.16 147.32 0)
			(effects
				(font
					(size 1.27 1.27)
					(thickness 0.15)
				)
				(justify left bottom)
				(hide yes)
			)
		)
		(property "Val" "10k"
			(at 238.76 166.37 90)
			(effects
				(font
					(size 1.27 1.27)
					(thickness 0.15)
				)
				(justify right)
			)
		)
		(property "Tolerance" "1%"
			(at 246.38 147.32 0)
			(effects
				(font
					(size 1.27 1.27)
				)
				(justify left bottom)
				(hide yes)
			)
		)
		(property "Public" ""
			(at 266.7 147.32 0)
			(effects
				(font
					(size 1.27 1.27)
				)
				(justify left bottom)
				(hide yes)
			)
		)
		(pin "1"
		)
		(pin "2"
		)
		(instances
			(project "polarfire-som"
				(path ""
					(reference "R46")
					(unit 1)
				)
			)
		)
	)
	(symbol
		(lib_id "antmicropower:GND")
		(at 190.5 229.87 0)
		(unit 1)
		(exclude_from_sim no)
		(in_bom yes)
		(on_board yes)
		(dnp no)
		(property "Reference" "#PWR051"
			(at 199.39 232.41 0)
			(effects
				(font
					(size 1.27 1.27)
					(thickness 0.15)
				)
				(justify left bottom)
				(hide yes)
			)
		)
		(property "Value" "GND"
			(at 190.5 233.68 0)
			(effects
				(font
					(size 1.27 1.27)
					(thickness 0.15)
				)
			)
		)
		(property "Footprint" ""
			(at 199.39 237.49 0)
			(effects
				(font
					(size 1.27 1.27)
					(thickness 0.15)
				)
				(justify left bottom)
				(hide yes)
			)
		)
		(property "Datasheet" ""
			(at 199.39 242.57 0)
			(effects
				(font
					(size 1.27 1.27)
					(thickness 0.15)
				)
				(justify left bottom)
				(hide yes)
			)
		)
		(property "Description" ""
			(at 190.5 229.87 0)
			(effects
				(font
					(size 1.27 1.27)
				)
				(hide yes)
			)
		)
		(property "Author" "Antmicro"
			(at 199.39 237.49 0)
			(effects
				(font
					(size 1.27 1.27)
					(thickness 0.15)
				)
				(justify left bottom)
				(hide yes)
			)
		)
		(property "License" "Apache-2.0"
			(at 199.39 240.03 0)
			(effects
				(font
					(size 1.27 1.27)
					(thickness 0.15)
				)
				(justify left bottom)
				(hide yes)
			)
		)
		(pin "1"
		)
		(instances
			(project "polarfire-som"
				(path ""
					(reference "#PWR051")
					(unit 1)
				)
			)
		)
	)
	(symbol
		(lib_id "antmicropower:+3V3")
		(at 252.73 160.02 0)
		(unit 1)
		(exclude_from_sim no)
		(in_bom yes)
		(on_board yes)
		(dnp no)
		(property "Reference" "#PWR058"
			(at 267.97 162.56 0)
			(effects
				(font
					(size 1.27 1.27)
					(thickness 0.15)
				)
				(justify left bottom)
				(hide yes)
			)
		)
		(property "Value" "+3V3"
			(at 252.73 156.21 0)
			(effects
				(font
					(size 1.27 1.27)
					(thickness 0.15)
				)
			)
		)
		(property "Footprint" ""
			(at 267.97 167.64 0)
			(effects
				(font
					(size 1.27 1.27)
					(thickness 0.15)
				)
				(justify left bottom)
				(hide yes)
			)
		)
		(property "Datasheet" ""
			(at 267.97 170.18 0)
			(effects
				(font
					(size 1.27 1.27)
					(thickness 0.15)
				)
				(justify left bottom)
				(hide yes)
			)
		)
		(property "Description" ""
			(at 252.73 160.02 0)
			(effects
				(font
					(size 1.27 1.27)
				)
				(hide yes)
			)
		)
		(property "Author" "Antmicro"
			(at 267.97 167.64 0)
			(effects
				(font
					(size 1.27 1.27)
					(thickness 0.15)
				)
				(justify left bottom)
				(hide yes)
			)
		)
		(property "License" "Apache-2.0"
			(at 267.97 170.18 0)
			(effects
				(font
					(size 1.27 1.27)
					(thickness 0.15)
				)
				(justify left bottom)
				(hide yes)
			)
		)
		(pin "1"
		)
		(instances
			(project "polarfire-som"
				(path ""
					(reference "#PWR058")
					(unit 1)
				)
			)
		)
	)
	(symbol
		(lib_id "antmicropower:+3V3")
		(at 236.22 160.02 0)
		(unit 1)
		(exclude_from_sim no)
		(in_bom yes)
		(on_board yes)
		(dnp no)
		(property "Reference" "#PWR060"
			(at 251.46 162.56 0)
			(effects
				(font
					(size 1.27 1.27)
					(thickness 0.15)
				)
				(justify left bottom)
				(hide yes)
			)
		)
		(property "Value" "+3V3"
			(at 236.22 156.21 0)
			(effects
				(font
					(size 1.27 1.27)
					(thickness 0.15)
				)
			)
		)
		(property "Footprint" ""
			(at 251.46 167.64 0)
			(effects
				(font
					(size 1.27 1.27)
					(thickness 0.15)
				)
				(justify left bottom)
				(hide yes)
			)
		)
		(property "Datasheet" ""
			(at 251.46 170.18 0)
			(effects
				(font
					(size 1.27 1.27)
					(thickness 0.15)
				)
				(justify left bottom)
				(hide yes)
			)
		)
		(property "Description" ""
			(at 236.22 160.02 0)
			(effects
				(font
					(size 1.27 1.27)
				)
				(hide yes)
			)
		)
		(property "Author" "Antmicro"
			(at 251.46 167.64 0)
			(effects
				(font
					(size 1.27 1.27)
					(thickness 0.15)
				)
				(justify left bottom)
				(hide yes)
			)
		)
		(property "License" "Apache-2.0"
			(at 251.46 170.18 0)
			(effects
				(font
					(size 1.27 1.27)
					(thickness 0.15)
				)
				(justify left bottom)
				(hide yes)
			)
		)
		(pin "1"
		)
		(instances
			(project "polarfire-som"
				(path ""
					(reference "#PWR060")
					(unit 1)
				)
			)
		)
	)
	(symbol
		(lib_id "antmicropower:+3V3")
		(at 223.52 226.06 270)
		(unit 1)
		(exclude_from_sim no)
		(in_bom yes)
		(on_board yes)
		(dnp no)
		(property "Reference" "#PWR0195"
			(at 223.52 241.3 0)
			(effects
				(font
					(size 1.27 1.27)
					(thickness 0.15)
				)
				(justify left bottom)
				(hide yes)
			)
		)
		(property "Value" "+3V3"
			(at 229.87 226.06 90)
			(effects
				(font
					(size 1.27 1.27)
					(thickness 0.15)
				)
			)
		)
		(property "Footprint" ""
			(at 215.9 241.3 0)
			(effects
				(font
					(size 1.27 1.27)
					(thickness 0.15)
				)
				(justify left bottom)
				(hide yes)
			)
		)
		(property "Datasheet" ""
			(at 213.36 241.3 0)
			(effects
				(font
					(size 1.27 1.27)
					(thickness 0.15)
				)
				(justify left bottom)
				(hide yes)
			)
		)
		(property "Description" ""
			(at 223.52 226.06 0)
			(effects
				(font
					(size 1.27 1.27)
				)
				(hide yes)
			)
		)
		(property "Author" "Antmicro"
			(at 220.98 241.3 0)
			(effects
				(font
					(size 1.27 1.27)
					(thickness 0.15)
				)
				(justify left bottom)
				(hide yes)
			)
		)
		(property "License" "Apache-2.0"
			(at 218.44 241.3 0)
			(effects
				(font
					(size 1.27 1.27)
					(thickness 0.15)
				)
				(justify left bottom)
				(hide yes)
			)
		)
		(pin "1"
		)
		(instances
			(project "polarfire-som"
				(path ""
					(reference "#PWR0195")
					(unit 1)
				)
			)
		)
	)
	(symbol
		(lib_id "antmicroResistors0402:R_10k_0402")
		(at 227.33 167.64 90)
		(unit 1)
		(exclude_from_sim no)
		(in_bom yes)
		(on_board yes)
		(dnp no)
		(fields_autoplaced yes)
		(property "Reference" "R45"
			(at 229.87 163.83 90)
			(effects
				(font
					(size 1.27 1.27)
					(thickness 0.15)
				)
				(justify right)
			)
		)
		(property "Value" "R_10k_0402"
			(at 240.03 147.32 0)
			(effects
				(font
					(size 1.27 1.27)
					(thickness 0.15)
				)
				(justify left bottom)
				(hide yes)
			)
		)
		(property "Footprint" "antmicro-footprints:R_0402_1005Metric"
			(at 242.57 147.32 0)
			(effects
				(font
					(size 1.27 1.27)
					(thickness 0.15)
				)
				(justify left bottom)
				(hide yes)
			)
		)
		(property "Datasheet" "https://www.bourns.com/docs/product-datasheets/cr.pdf"
			(at 245.11 147.32 0)
			(effects
				(font
					(size 1.27 1.27)
					(thickness 0.15)
				)
				(justify left bottom)
				(hide yes)
			)
		)
		(property "Description" "SMD Chip Resistor, 10 kohm, ± 1%, 62.5 mW, 0402 [1005 Metric], Thick Film, General Purpose"
			(at 227.33 167.64 0)
			(effects
				(font
					(size 1.27 1.27)
				)
				(hide yes)
			)
		)
		(property "MPN" "CR0402-FX-1002GLF"
			(at 247.65 147.32 0)
			(effects
				(font
					(size 1.27 1.27)
					(thickness 0.15)
				)
				(justify left bottom)
				(hide yes)
			)
		)
		(property "Manufacturer" "Bourns"
			(at 250.19 147.32 0)
			(effects
				(font
					(size 1.27 1.27)
					(thickness 0.15)
				)
				(justify left bottom)
				(hide yes)
			)
		)
		(property "License" "Apache-2.0"
			(at 252.73 147.32 0)
			(effects
				(font
					(size 1.27 1.27)
					(thickness 0.15)
				)
				(justify left bottom)
				(hide yes)
			)
		)
		(property "Author" "Antmicro"
			(at 255.27 147.32 0)
			(effects
				(font
					(size 1.27 1.27)
					(thickness 0.15)
				)
				(justify left bottom)
				(hide yes)
			)
		)
		(property "Val" "10k"
			(at 229.87 166.37 90)
			(effects
				(font
					(size 1.27 1.27)
					(thickness 0.15)
				)
				(justify right)
			)
		)
		(property "Tolerance" "1%"
			(at 237.49 147.32 0)
			(effects
				(font
					(size 1.27 1.27)
				)
				(justify left bottom)
				(hide yes)
			)
		)
		(property "Public" ""
			(at 257.81 147.32 0)
			(effects
				(font
					(size 1.27 1.27)
				)
				(justify left bottom)
				(hide yes)
			)
		)
		(pin "1"
		)
		(pin "2"
		)
		(instances
			(project "polarfire-som"
				(path ""
					(reference "R45")
					(unit 1)
				)
			)
		)
	)
	(symbol
		(lib_id "antmicropower:+3V3")
		(at 227.33 160.02 0)
		(unit 1)
		(exclude_from_sim no)
		(in_bom yes)
		(on_board yes)
		(dnp no)
		(property "Reference" "#PWR057"
			(at 242.57 162.56 0)
			(effects
				(font
					(size 1.27 1.27)
					(thickness 0.15)
				)
				(justify left bottom)
				(hide yes)
			)
		)
		(property "Value" "+3V3"
			(at 227.33 156.21 0)
			(effects
				(font
					(size 1.27 1.27)
					(thickness 0.15)
				)
			)
		)
		(property "Footprint" ""
			(at 242.57 167.64 0)
			(effects
				(font
					(size 1.27 1.27)
					(thickness 0.15)
				)
				(justify left bottom)
				(hide yes)
			)
		)
		(property "Datasheet" ""
			(at 242.57 170.18 0)
			(effects
				(font
					(size 1.27 1.27)
					(thickness 0.15)
				)
				(justify left bottom)
				(hide yes)
			)
		)
		(property "Description" ""
			(at 227.33 160.02 0)
			(effects
				(font
					(size 1.27 1.27)
				)
				(hide yes)
			)
		)
		(property "Author" "Antmicro"
			(at 242.57 167.64 0)
			(effects
				(font
					(size 1.27 1.27)
					(thickness 0.15)
				)
				(justify left bottom)
				(hide yes)
			)
		)
		(property "License" "Apache-2.0"
			(at 242.57 170.18 0)
			(effects
				(font
					(size 1.27 1.27)
					(thickness 0.15)
				)
				(justify left bottom)
				(hide yes)
			)
		)
		(pin "1"
		)
		(instances
			(project "polarfire-som"
				(path ""
					(reference "#PWR057")
					(unit 1)
				)
			)
		)
	)
	(symbol
		(lib_id "antmicroResistors0402:R_4k7_0402")
		(at 165.1 91.44 0)
		(unit 1)
		(exclude_from_sim no)
		(in_bom yes)
		(on_board yes)
		(dnp no)
		(property "Reference" "R41"
			(at 163.195 89.535 0)
			(effects
				(font
					(size 1.27 1.27)
					(thickness 0.15)
				)
			)
		)
		(property "Value" "R_4k7_0402"
			(at 185.42 104.14 0)
			(effects
				(font
					(size 1.27 1.27)
					(thickness 0.15)
				)
				(justify left bottom)
				(hide yes)
			)
		)
		(property "Footprint" "antmicro-footprints:R_0402_1005Metric"
			(at 185.42 106.68 0)
			(effects
				(font
					(size 1.27 1.27)
					(thickness 0.15)
				)
				(justify left bottom)
				(hide yes)
			)
		)
		(property "Datasheet" "https://www.bourns.com/docs/product-datasheets/cr.pdf"
			(at 185.42 109.22 0)
			(effects
				(font
					(size 1.27 1.27)
					(thickness 0.15)
				)
				(justify left bottom)
				(hide yes)
			)
		)
		(property "Description" "SMD Chip Resistor, 4.7 kohm, ± 1%, 62.5 mW, 0402 [1005 Metric], Thick Film, General Purpose"
			(at 165.1 91.44 0)
			(effects
				(font
					(size 1.27 1.27)
				)
				(hide yes)
			)
		)
		(property "MPN" "CR0402-FX-4701GLF"
			(at 185.42 111.76 0)
			(effects
				(font
					(size 1.27 1.27)
					(thickness 0.15)
				)
				(justify left bottom)
				(hide yes)
			)
		)
		(property "Manufacturer" "Bourns"
			(at 185.42 114.3 0)
			(effects
				(font
					(size 1.27 1.27)
					(thickness 0.15)
				)
				(justify left bottom)
				(hide yes)
			)
		)
		(property "License" "Apache-2.0"
			(at 185.42 116.84 0)
			(effects
				(font
					(size 1.27 1.27)
					(thickness 0.15)
				)
				(justify left bottom)
				(hide yes)
			)
		)
		(property "Author" "Antmicro"
			(at 185.42 119.38 0)
			(effects
				(font
					(size 1.27 1.27)
					(thickness 0.15)
				)
				(justify left bottom)
				(hide yes)
			)
		)
		(property "Val" "4k7"
			(at 171.45 89.535 0)
			(effects
				(font
					(size 1.27 1.27)
					(thickness 0.15)
				)
			)
		)
		(property "Tolerance" "1%"
			(at 185.42 101.6 0)
			(effects
				(font
					(size 1.27 1.27)
				)
				(justify left bottom)
				(hide yes)
			)
		)
		(property "Public" ""
			(at 185.42 121.92 0)
			(effects
				(font
					(size 1.27 1.27)
				)
				(justify left bottom)
				(hide yes)
			)
		)
		(pin "1"
		)
		(pin "2"
		)
		(instances
			(project "polarfire-som"
				(path ""
					(reference "R41")
					(unit 1)
				)
			)
		)
	)
	(symbol
		(lib_id "antmicropower:GND")
		(at 219.71 107.95 0)
		(unit 1)
		(exclude_from_sim no)
		(in_bom yes)
		(on_board yes)
		(dnp no)
		(fields_autoplaced yes)
		(property "Reference" "#PWR0276"
			(at 228.6 110.49 0)
			(effects
				(font
					(size 1.27 1.27)
					(thickness 0.15)
				)
				(justify left bottom)
				(hide yes)
			)
		)
		(property "Value" "GND"
			(at 219.71 113.03 0)
			(effects
				(font
					(size 1.27 1.27)
					(thickness 0.15)
				)
			)
		)
		(property "Footprint" ""
			(at 228.6 115.57 0)
			(effects
				(font
					(size 1.27 1.27)
					(thickness 0.15)
				)
				(justify left bottom)
				(hide yes)
			)
		)
		(property "Datasheet" ""
			(at 228.6 120.65 0)
			(effects
				(font
					(size 1.27 1.27)
					(thickness 0.15)
				)
				(justify left bottom)
				(hide yes)
			)
		)
		(property "Description" ""
			(at 219.71 107.95 0)
			(effects
				(font
					(size 1.27 1.27)
				)
				(hide yes)
			)
		)
		(property "Author" "Antmicro"
			(at 228.6 115.57 0)
			(effects
				(font
					(size 1.27 1.27)
					(thickness 0.15)
				)
				(justify left bottom)
				(hide yes)
			)
		)
		(property "License" "Apache-2.0"
			(at 228.6 118.11 0)
			(effects
				(font
					(size 1.27 1.27)
					(thickness 0.15)
				)
				(justify left bottom)
				(hide yes)
			)
		)
		(pin "1"
		)
		(instances
			(project "polarfire-som"
				(path ""
					(reference "#PWR0276")
					(unit 1)
				)
			)
		)
	)
	(symbol
		(lib_id "antmicroResistors0402:R_0R_0402")
		(at 261.62 93.98 0)
		(unit 1)
		(exclude_from_sim no)
		(in_bom yes)
		(on_board yes)
		(dnp yes)
		(property "Reference" "R90"
			(at 259.08 92.71 0)
			(effects
				(font
					(size 1.27 1.27)
					(thickness 0.15)
				)
			)
		)
		(property "Value" "R_0R_0402"
			(at 281.94 106.68 0)
			(effects
				(font
					(size 1.27 1.27)
					(thickness 0.15)
				)
				(justify left bottom)
				(hide yes)
			)
		)
		(property "Footprint" "antmicro-footprints:R_0402_1005Metric"
			(at 281.94 109.22 0)
			(effects
				(font
					(size 1.27 1.27)
					(thickness 0.15)
				)
				(justify left bottom)
				(hide yes)
			)
		)
		(property "Datasheet" "https://industrial.panasonic.com/cdbs/www-data/pdf/RDA0000/AOA0000C301.pdf"
			(at 281.94 111.76 0)
			(effects
				(font
					(size 1.27 1.27)
					(thickness 0.15)
				)
				(justify left bottom)
				(hide yes)
			)
		)
		(property "Description" "SMD Chip Resistor, Jumper, 0 ohm, 100 mW, 0402 [1005 Metric], Thick Film, General Purpose"
			(at 261.62 93.98 0)
			(effects
				(font
					(size 1.27 1.27)
				)
				(hide yes)
			)
		)
		(property "MPN" "ERJ2GE0R00X"
			(at 281.94 114.3 0)
			(effects
				(font
					(size 1.27 1.27)
					(thickness 0.15)
				)
				(justify left bottom)
				(hide yes)
			)
		)
		(property "Manufacturer" "Panasonic"
			(at 281.94 116.84 0)
			(effects
				(font
					(size 1.27 1.27)
					(thickness 0.15)
				)
				(justify left bottom)
				(hide yes)
			)
		)
		(property "License" "Apache-2.0"
			(at 281.94 119.38 0)
			(effects
				(font
					(size 1.27 1.27)
					(thickness 0.15)
				)
				(justify left bottom)
				(hide yes)
			)
		)
		(property "Author" "Antmicro"
			(at 281.94 121.92 0)
			(effects
				(font
					(size 1.27 1.27)
					(thickness 0.15)
				)
				(justify left bottom)
				(hide yes)
			)
		)
		(property "Val" "0R"
			(at 269.24 92.71 0)
			(effects
				(font
					(size 1.27 1.27)
					(thickness 0.15)
				)
			)
		)
		(property "Tolerance" "~"
			(at 281.94 104.14 0)
			(effects
				(font
					(size 1.27 1.27)
				)
				(justify left bottom)
				(hide yes)
			)
		)
		(property "Current" "1A"
			(at 281.94 124.46 0)
			(effects
				(font
					(size 1.27 1.27)
					(thickness 0.15)
				)
				(justify left bottom)
				(hide yes)
			)
		)
		(property "Public" ""
			(at 281.94 124.46 0)
			(effects
				(font
					(size 1.27 1.27)
				)
				(justify left bottom)
				(hide yes)
			)
		)
		(pin "1"
		)
		(pin "2"
		)
		(instances
			(project "polarfire-som"
				(path ""
					(reference "R90")
					(unit 1)
				)
			)
		)
	)
	(symbol
		(lib_id "antmicropower:+3V3")
		(at 158.75 78.74 0)
		(unit 1)
		(exclude_from_sim no)
		(in_bom yes)
		(on_board yes)
		(dnp no)
		(fields_autoplaced yes)
		(property "Reference" "#PWR053"
			(at 173.99 81.28 0)
			(effects
				(font
					(size 1.27 1.27)
					(thickness 0.15)
				)
				(justify left bottom)
				(hide yes)
			)
		)
		(property "Value" "+3V3"
			(at 158.75 73.66 0)
			(effects
				(font
					(size 1.27 1.27)
					(thickness 0.15)
				)
			)
		)
		(property "Footprint" ""
			(at 173.99 86.36 0)
			(effects
				(font
					(size 1.27 1.27)
					(thickness 0.15)
				)
				(justify left bottom)
				(hide yes)
			)
		)
		(property "Datasheet" ""
			(at 173.99 88.9 0)
			(effects
				(font
					(size 1.27 1.27)
					(thickness 0.15)
				)
				(justify left bottom)
				(hide yes)
			)
		)
		(property "Description" ""
			(at 158.75 78.74 0)
			(effects
				(font
					(size 1.27 1.27)
				)
				(hide yes)
			)
		)
		(property "Author" "Antmicro"
			(at 173.99 86.36 0)
			(effects
				(font
					(size 1.27 1.27)
					(thickness 0.15)
				)
				(justify left bottom)
				(hide yes)
			)
		)
		(property "License" "Apache-2.0"
			(at 173.99 88.9 0)
			(effects
				(font
					(size 1.27 1.27)
					(thickness 0.15)
				)
				(justify left bottom)
				(hide yes)
			)
		)
		(pin "1"
		)
		(instances
			(project "polarfire-som"
				(path ""
					(reference "#PWR053")
					(unit 1)
				)
			)
		)
	)
	(symbol
		(lib_id "antmicroTestPoints:Tag-Connect_TC2050-IDC-NL_2x5_P1.27mm")
		(at 191.77 215.9 0)
		(unit 1)
		(exclude_from_sim no)
		(in_bom no)
		(on_board yes)
		(dnp yes)
		(property "Reference" "J2"
			(at 206.756 208.788 0)
			(effects
				(font
					(size 1.27 1.27)
					(thickness 0.15)
				)
			)
		)
		(property "Value" "Tag-Connect_TC2050-IDC-NL_2x5_P1.27mm"
			(at 212.09 218.44 0)
			(effects
				(font
					(size 1.27 1.27)
					(thickness 0.15)
				)
				(justify left bottom)
				(hide yes)
			)
		)
		(property "Footprint" "antmicro-footprints:Tag-Connect_TC2050-IDC-NL_2x5_P1.27mm"
			(at 212.09 220.98 0)
			(effects
				(font
					(size 1.27 1.27)
					(thickness 0.15)
				)
				(justify left bottom)
				(hide yes)
			)
		)
		(property "Datasheet" "https://www.tag-connect.com/wp-content/uploads/bsk-pdf-manager/TC2050-IDC-NL_Datasheet_8.pdf"
			(at 212.09 223.52 0)
			(effects
				(font
					(size 1.27 1.27)
					(thickness 0.15)
				)
				(justify left bottom)
				(hide yes)
			)
		)
		(property "Description" "Tag Connect 2x5 1.27mm terminal"
			(at 191.77 215.9 0)
			(effects
				(font
					(size 1.27 1.27)
				)
				(hide yes)
			)
		)
		(property "MPN" "TC2050-IDC-NL"
			(at 206.756 211.328 0)
			(effects
				(font
					(size 1.27 1.27)
					(thickness 0.15)
				)
			)
		)
		(property "Manufacturer" "Tag Connect"
			(at 212.09 228.6 0)
			(effects
				(font
					(size 1.27 1.27)
					(thickness 0.15)
				)
				(justify left bottom)
				(hide yes)
			)
		)
		(property "Author" "Antmicro"
			(at 212.09 231.14 0)
			(effects
				(font
					(size 1.27 1.27)
					(thickness 0.15)
				)
				(justify left bottom)
				(hide yes)
			)
		)
		(property "License" "Apache-2.0"
			(at 212.09 233.68 0)
			(effects
				(font
					(size 1.27 1.27)
					(thickness 0.15)
				)
				(justify left bottom)
				(hide yes)
			)
		)
		(property "DNP" "DNP"
			(at 191.77 215.9 0)
			(effects
				(font
					(size 1.27 1.27)
				)
				(hide yes)
			)
		)
		(pin "1"
		)
		(pin "6"
		)
		(pin "4"
		)
		(pin "3"
		)
		(pin "2"
		)
		(pin "8"
		)
		(pin "9"
		)
		(pin "7"
		)
		(pin "10"
		)
		(pin "5"
		)
		(instances
			(project "polarfire-som"
				(path ""
					(reference "J2")
					(unit 1)
				)
			)
		)
	)
	(symbol
		(lib_id "antmicropower:GND")
		(at 172.72 172.72 0)
		(unit 1)
		(exclude_from_sim no)
		(in_bom yes)
		(on_board yes)
		(dnp no)
		(fields_autoplaced yes)
		(property "Reference" "#PWR055"
			(at 181.61 175.26 0)
			(effects
				(font
					(size 1.27 1.27)
					(thickness 0.15)
				)
				(justify left bottom)
				(hide yes)
			)
		)
		(property "Value" "GND"
			(at 172.72 177.8 0)
			(effects
				(font
					(size 1.27 1.27)
					(thickness 0.15)
				)
			)
		)
		(property "Footprint" ""
			(at 181.61 180.34 0)
			(effects
				(font
					(size 1.27 1.27)
					(thickness 0.15)
				)
				(justify left bottom)
				(hide yes)
			)
		)
		(property "Datasheet" ""
			(at 181.61 185.42 0)
			(effects
				(font
					(size 1.27 1.27)
					(thickness 0.15)
				)
				(justify left bottom)
				(hide yes)
			)
		)
		(property "Description" ""
			(at 172.72 172.72 0)
			(effects
				(font
					(size 1.27 1.27)
				)
				(hide yes)
			)
		)
		(property "Author" "Antmicro"
			(at 181.61 180.34 0)
			(effects
				(font
					(size 1.27 1.27)
					(thickness 0.15)
				)
				(justify left bottom)
				(hide yes)
			)
		)
		(property "License" "Apache-2.0"
			(at 181.61 182.88 0)
			(effects
				(font
					(size 1.27 1.27)
					(thickness 0.15)
				)
				(justify left bottom)
				(hide yes)
			)
		)
		(pin "1"
		)
		(instances
			(project "polarfire-som"
				(path ""
					(reference "#PWR055")
					(unit 1)
				)
			)
		)
	)
	(symbol
		(lib_id "antmicropower:+3V3")
		(at 217.17 74.93 0)
		(unit 1)
		(exclude_from_sim no)
		(in_bom yes)
		(on_board yes)
		(dnp no)
		(fields_autoplaced yes)
		(property "Reference" "#PWR056"
			(at 232.41 77.47 0)
			(effects
				(font
					(size 1.27 1.27)
					(thickness 0.15)
				)
				(justify left bottom)
				(hide yes)
			)
		)
		(property "Value" "+3V3"
			(at 217.17 69.85 0)
			(effects
				(font
					(size 1.27 1.27)
					(thickness 0.15)
				)
			)
		)
		(property "Footprint" ""
			(at 232.41 82.55 0)
			(effects
				(font
					(size 1.27 1.27)
					(thickness 0.15)
				)
				(justify left bottom)
				(hide yes)
			)
		)
		(property "Datasheet" ""
			(at 232.41 85.09 0)
			(effects
				(font
					(size 1.27 1.27)
					(thickness 0.15)
				)
				(justify left bottom)
				(hide yes)
			)
		)
		(property "Description" ""
			(at 217.17 74.93 0)
			(effects
				(font
					(size 1.27 1.27)
				)
				(hide yes)
			)
		)
		(property "Author" "Antmicro"
			(at 232.41 82.55 0)
			(effects
				(font
					(size 1.27 1.27)
					(thickness 0.15)
				)
				(justify left bottom)
				(hide yes)
			)
		)
		(property "License" "Apache-2.0"
			(at 232.41 85.09 0)
			(effects
				(font
					(size 1.27 1.27)
					(thickness 0.15)
				)
				(justify left bottom)
				(hide yes)
			)
		)
		(pin "1"
		)
		(instances
			(project "polarfire-som"
				(path ""
					(reference "#PWR056")
					(unit 1)
				)
			)
		)
	)
	(symbol
		(lib_id "antmicropower:GND")
		(at 257.81 69.85 0)
		(mirror y)
		(unit 1)
		(exclude_from_sim no)
		(in_bom yes)
		(on_board yes)
		(dnp no)
		(fields_autoplaced yes)
		(property "Reference" "#PWR366"
			(at 248.92 72.39 0)
			(effects
				(font
					(size 1.27 1.27)
					(thickness 0.15)
				)
				(justify left bottom)
				(hide yes)
			)
		)
		(property "Value" "GND"
			(at 257.81 74.93 0)
			(effects
				(font
					(size 1.27 1.27)
					(thickness 0.15)
				)
			)
		)
		(property "Footprint" ""
			(at 248.92 77.47 0)
			(effects
				(font
					(size 1.27 1.27)
					(thickness 0.15)
				)
				(justify left bottom)
				(hide yes)
			)
		)
		(property "Datasheet" ""
			(at 248.92 82.55 0)
			(effects
				(font
					(size 1.27 1.27)
					(thickness 0.15)
				)
				(justify left bottom)
				(hide yes)
			)
		)
		(property "Description" ""
			(at 257.81 69.85 0)
			(effects
				(font
					(size 1.27 1.27)
				)
				(hide yes)
			)
		)
		(property "Author" "Antmicro"
			(at 248.92 77.47 0)
			(effects
				(font
					(size 1.27 1.27)
					(thickness 0.15)
				)
				(justify left bottom)
				(hide yes)
			)
		)
		(property "License" "Apache-2.0"
			(at 248.92 80.01 0)
			(effects
				(font
					(size 1.27 1.27)
					(thickness 0.15)
				)
				(justify left bottom)
				(hide yes)
			)
		)
		(pin "1"
		)
		(instances
			(project "polarfire-som"
				(path ""
					(reference "#PWR366")
					(unit 1)
				)
			)
		)
	)
	(symbol
		(lib_id "antmicroResistors0402:R_1k_0402")
		(at 217.17 81.28 90)
		(unit 1)
		(exclude_from_sim no)
		(in_bom yes)
		(on_board yes)
		(dnp no)
		(property "Reference" "R42"
			(at 218.44 77.47 90)
			(effects
				(font
					(size 1.27 1.27)
					(thickness 0.15)
				)
				(justify right)
			)
		)
		(property "Value" "R_1k_0402"
			(at 229.87 60.96 0)
			(effects
				(font
					(size 1.27 1.27)
					(thickness 0.15)
				)
				(justify left bottom)
				(hide yes)
			)
		)
		(property "Footprint" "antmicro-footprints:R_0402_1005Metric"
			(at 232.41 60.96 0)
			(effects
				(font
					(size 1.27 1.27)
					(thickness 0.15)
				)
				(justify left bottom)
				(hide yes)
			)
		)
		(property "Datasheet" "https://www.bourns.com/docs/product-datasheets/cr.pdf"
			(at 234.95 60.96 0)
			(effects
				(font
					(size 1.27 1.27)
					(thickness 0.15)
				)
				(justify left bottom)
				(hide yes)
			)
		)
		(property "Description" "SMD Chip Resistor, 1 kohm, ± 1%, 63 mW, 0402 [1005 Metric], Thick Film, General Purpose"
			(at 217.17 81.28 0)
			(effects
				(font
					(size 1.27 1.27)
				)
				(hide yes)
			)
		)
		(property "MPN" "CR0402-FX-1001GLF"
			(at 237.49 60.96 0)
			(effects
				(font
					(size 1.27 1.27)
					(thickness 0.15)
				)
				(justify left bottom)
				(hide yes)
			)
		)
		(property "Manufacturer" "Bourns"
			(at 240.03 60.96 0)
			(effects
				(font
					(size 1.27 1.27)
					(thickness 0.15)
				)
				(justify left bottom)
				(hide yes)
			)
		)
		(property "License" "Apache-2.0"
			(at 242.57 60.96 0)
			(effects
				(font
					(size 1.27 1.27)
					(thickness 0.15)
				)
				(justify left bottom)
				(hide yes)
			)
		)
		(property "Author" "Antmicro"
			(at 245.11 60.96 0)
			(effects
				(font
					(size 1.27 1.27)
					(thickness 0.15)
				)
				(justify left bottom)
				(hide yes)
			)
		)
		(property "Val" "1k"
			(at 218.44 80.01 90)
			(effects
				(font
					(size 1.27 1.27)
					(thickness 0.15)
				)
				(justify right)
			)
		)
		(property "Tolerance" "1%"
			(at 227.33 60.96 0)
			(effects
				(font
					(size 1.27 1.27)
				)
				(justify left bottom)
				(hide yes)
			)
		)
		(property "Public" ""
			(at 247.65 60.96 0)
			(effects
				(font
					(size 1.27 1.27)
				)
				(justify left bottom)
				(hide yes)
			)
		)
		(pin "2"
		)
		(pin "1"
		)
		(instances
			(project "polarfire-som"
				(path ""
					(reference "R42")
					(unit 1)
				)
			)
		)
	)
)
